G04 ================== begin FILE IDENTIFICATION RECORD ==================*
G04 Layout Name:  13130-1b.brd*
G04 Film Name:    L5*
G04 File Format:  Gerber RS274X*
G04 File Origin:  Cadence Allegro 16.5-S037*
G04 Origin Date:  Thu Nov 13 17:27:00 2014*
G04 *
G04 Layer:  VIA CLASS/L5*
G04 Layer:  PIN/L5*
G04 Layer:  ETCH/L5*
G04 Layer:  DRAWING FORMAT/LAYER_PCB_STORY*
G04 Layer:  DRAWING FORMAT/LAYER_L5*
G04 *
G04 Offset:    (0.00 0.00)*
G04 Mirror:    No*
G04 Mode:      Positive*
G04 Rotation:  0*
G04 FullContactRelief:  No*
G04 UndefLineWidth:     6.00*
G04 ================== end FILE IDENTIFICATION RECORD ====================*
%FSLAX35Y35*MOIN*%
%IR0*IPPOS*OFA0.00000B0.00000*MIA0B0*SFA1.00000B1.00000*%
%ADD11C,.02*%
%ADD12C,.022*%
%ADD14C,.017*%
%ADD10C,.028*%
%ADD13C,.056*%
%ADD15C,.01*%
%ADD16C,.011*%
%ADD17C,.012*%
%ADD18C,.04*%
%ADD19C,.025*%
%ADD20C,.004*%
%ADD21C,.006*%
%ADD22C,.005*%
%ADD23C,.008*%
%ADD24C,.0035*%
%ADD25C,.0045*%
%ADD30C,.03004*%
%ADD28C,.05204*%
%ADD29C,.04404*%
%ADD32C,.02704*%
%ADD34C,.04604*%
%ADD35C,.08404*%
%ADD36C,.06804*%
%ADD33C,.09176*%
%ADD31O,.21302X.15002*%
%ADD26C,.11004*%
%ADD27C,.15004*%
G75*
%LPD*%
G75*
G36*
G01X218800Y65000D02*
G02X219200Y64585I0J-400D01*
G03X221236Y62304I2200J-85D01*
G02X221605Y61874I-30J-399D01*
G03X223964Y63896I2195J-174D01*
G02X223595Y64326I30J399D01*
G03X223600Y64585I-2195J172D01*
G02X224000Y65000I400J15D01*
G01X228300D01*
G03X228649Y64661I1699J1400D01*
G01X228726Y64503D01*
X228682Y64378D01*
G03X232136Y64354I1718J-1378D01*
G02X232451Y65000I316J246D01*
G01X233091D01*
G02X233446Y64416I0J-400D01*
G03X233753Y61938I1954J-1016D01*
G02X233535Y61281I-299J-265D01*
G03X235628Y60587I447J-2156D01*
G02X235846Y61244I299J265D01*
G03X237354Y64416I-446J2156D01*
G02X237709Y65000I355J184D01*
G01X240210D01*
G03X240390I90J2200D01*
G01X255864D01*
X255906Y64857D01*
G03X260894I2494J743D01*
G01X260936Y65000D01*
X293454D01*
G03X297146I1846J1200D01*
G01X331125D01*
G02X331505Y64477I-1J-400D01*
G03X335695I2095J-677D01*
G02X336075Y65000I381J123D01*
G01X338155D01*
G03X341121I1483J2138D01*
G01X371500D01*
X383500Y53000D01*
Y48268D01*
G03Y45732I1800J-1268D01*
G01Y38500D01*
X381500Y36500D01*
X379500D01*
X376000Y40000D01*
X370500D01*
X369000Y41500D01*
Y46500D01*
X368668Y46832D01*
X368677Y46926D01*
G03X364818Y48569I-2193J203D01*
G01X364758Y48500D01*
X364301D01*
X364242Y48564D01*
G03X360427Y47189I-1616J-1496D01*
G01X360417Y47000D01*
X339250D01*
X334875Y42625D01*
X327625D01*
X325000Y40000D01*
X319000D01*
X317575Y41425D01*
X317562Y41448D01*
G03X317012Y41998I-1308J-758D01*
G01X316989Y42011D01*
X316500Y42500D01*
X255145D01*
X255112Y42512D01*
G03X254088I-512J-1412D01*
G01X254055Y42500D01*
X238116D01*
G02X237722Y42831I0J400D01*
G01X237719Y42848D01*
Y42940D01*
G03X237723Y43060I-1508J110D01*
G01X237719D01*
Y43064D01*
X237724D01*
Y43067D01*
X237723D01*
G03X236211Y44570I-1512J-9D01*
G01X232591D01*
G03X231248Y43752I1J-1513D01*
G02X230570Y43751I-339J212D01*
G03X227799Y42910I-1270J-802D01*
G02X227399Y42500I-400J-10D01*
G01X139000D01*
X137000Y40500D01*
X130500D01*
X128500Y42500D01*
X75500D01*
X73500Y40500D01*
X62500D01*
X61000Y42000D01*
Y58500D01*
X58500Y61000D01*
X5500D01*
X3000Y63500D01*
Y128500D01*
X5500Y131000D01*
X21500D01*
X23500Y129000D01*
Y119000D01*
X26500Y116000D01*
Y109000D01*
X30399Y105101D01*
X30398Y105018D01*
G03X33018Y102398I2602J-18D01*
G01X33101Y102399D01*
X39821Y95679D01*
X39831Y95617D01*
G03X42921Y94000I2169J383D01*
G01X63000D01*
X66073Y90927D01*
X66088Y90878D01*
G03X67578Y89388I2112J622D01*
G01X67627Y89373D01*
X68000Y89000D01*
X75500D01*
X99500Y65000D01*
X107159D01*
G02X107534Y64462I0J-400D01*
G03X108095Y62093I2066J-762D01*
G02X108110Y61524I-273J-292D01*
G03X111205Y61607I1589J-1524D01*
G02X111190Y62176I273J292D01*
G03X111666Y64462I-1590J1524D01*
G02X112041Y65000I375J138D01*
G01X142591D01*
G03X145409I1409J2875D01*
G01X161790D01*
X161806Y64817D01*
G03X166194I2194J183D01*
G01X166210Y65000D01*
X177708D01*
X177758Y64875D01*
G03X181842I2042J825D01*
G01X181892Y65000D01*
X182500D01*
X187500Y60000D01*
X202500D01*
X207500Y65000D01*
X218800D01*
G37*
G36*
G01X32602Y135602D02*
G02X32202Y136001I0J400D01*
G03X28444Y137558I-2202J-1D01*
G02X27878I-283J283D01*
G01X20302Y145134D01*
Y167751D01*
X12452Y175601D01*
Y215549D01*
X20200Y223298D01*
Y267752D01*
X19099Y268854D01*
X19101Y268940D01*
G03X16960Y266799I-2201J60D01*
G01X17046Y266801D01*
X17298Y266550D01*
Y224500D01*
X9548Y216751D01*
Y174399D01*
X17398Y166549D01*
Y143932D01*
X28632Y132698D01*
X50516D01*
G02X50843Y132068I0J-400D01*
G03X52362Y128616I1800J-1268D01*
G01X52429Y128607D01*
X55238Y125798D01*
X63447D01*
G02X63763Y125153I0J-400D01*
G03X67119Y125292I1737J-1353D01*
G02X67273Y125938I294J271D01*
G03X64655Y129202I-773J2062D01*
G01X58458D01*
G02X58096Y129770I1J400D01*
G03X57837Y132053I-1996J930D01*
G02X58153Y132698I316J245D01*
G01X77949D01*
X91499Y119148D01*
X98852D01*
X100500Y117500D01*
Y103500D01*
X107000Y97000D01*
Y85500D01*
X104000Y82500D01*
X93858D01*
G02X93496Y83069I0J400D01*
G03X92153Y86103I-1996J931D01*
G02X91891Y86610I118J382D01*
G03X91428Y88782I-2091J690D01*
G02X91459Y89351I296J269D01*
G03X88372Y89518I-1459J1649D01*
G02X88341Y88949I-296J-269D01*
G03X89147Y85197I1459J-1649D01*
G02X89409Y84690I-118J-382D01*
G03X89504Y83069I2091J-691D01*
G02X89142Y82500I-362J-169D01*
G01X85500D01*
X72500Y95500D01*
X70323D01*
X70276Y95633D01*
G03X66124I-2076J-733D01*
G01X66077Y95500D01*
X45500D01*
X44000Y97000D01*
Y103336D01*
G03X43209Y107304I-2000J1664D01*
G01X43182Y107318D01*
X42500Y108000D01*
X30500D01*
X28000Y110500D01*
Y128000D01*
X23000Y133000D01*
X5500D01*
X3000Y135500D01*
Y192000D01*
X3001Y192001D01*
Y286501D01*
X4000Y287500D01*
X37500D01*
X38500Y286500D01*
Y268500D01*
X42000Y265000D01*
Y226500D01*
X49500Y219000D01*
X55238D01*
G03X59336I2049J806D01*
G01X59500D01*
X63500Y223000D01*
Y265500D01*
X65000Y267000D01*
X70532D01*
G03X73020Y266967I1268J1800D01*
G01X73070Y267000D01*
X73500D01*
X76198Y269698D01*
X78298D01*
Y269499D01*
G03X82058Y267944I2202J1D01*
G02X82342I142J-141D01*
G03Y271056I1558J1556D01*
G02X82058I-142J141D01*
G03X81010Y271642I-1558J-1556D01*
G02X80820Y272314I93J389D01*
G01X83506Y275000D01*
X171500D01*
X181500Y265000D01*
X250500D01*
X254500Y261000D01*
Y251000D01*
X253000Y249500D01*
X224500D01*
X221000Y246000D01*
Y235000D01*
X206500Y220500D01*
X137000D01*
X130500Y214000D01*
X100500D01*
X96898Y217602D01*
G03X96609Y217892I-1697J-1403D01*
G01X96602Y217898D01*
X96500Y218000D01*
X96470D01*
X96420Y218033D01*
G03X93932Y218000I-1220J-1833D01*
G01X80000D01*
X75500Y213500D01*
X42000D01*
X41500Y214000D01*
X41154D01*
X41110Y214024D01*
G03X39690I-710J-1324D01*
G01X39646Y214000D01*
X39500D01*
X38500Y213000D01*
Y207500D01*
X35500Y204500D01*
Y198151D01*
G02X34854Y197836I-400J1D01*
G03X33754Y198287I-1354J-1736D01*
G02X33421Y198814I46J398D01*
G03X33502Y199336I-1421J488D01*
G01Y203164D01*
G03X30498I-1502J36D01*
G01Y199336D01*
G03X31464Y197897I1502J-36D01*
G02X31657Y197304I-142J-374D01*
G03X31342Y196537I1843J-1205D01*
G01X31330Y196477D01*
X30654Y195802D01*
X18454D01*
X15698Y193046D01*
Y191466D01*
G03X18854Y188464I1802J-1266D01*
G02X19500Y188149I246J-316D01*
G01Y173000D01*
X21500Y171000D01*
X33500D01*
X34000Y171500D01*
Y175950D01*
X34142Y175994D01*
G03X34879Y179817I-642J2106D01*
G02X34850Y180100I125J156D01*
G03X34000Y183531I-1700J1400D01*
G01Y192000D01*
X35760Y193760D01*
G02X36328Y193758I283J-283D01*
G03X37953Y193099I1572J1542D01*
G02X38355Y192619I10J-400D01*
G03X40597Y195646I4362J-887D01*
G02X40021Y195891I-190J352D01*
G03X39442Y196872I-2121J-591D01*
G02X39440Y197440I281J285D01*
G01X39500Y197500D01*
X57500D01*
X60658Y194342D01*
X60671Y194288D01*
G03X62588Y192371I2529J612D01*
G01X62642Y192358D01*
X90500Y164500D01*
Y156000D01*
X111000Y135500D01*
X114180D01*
X115298Y134382D01*
Y133404D01*
X116000Y132702D01*
Y131500D01*
X108752Y124252D01*
X93613D01*
X85346Y132518D01*
G02X85609Y133201I283J283D01*
G03X83301Y135509I-109J2199D01*
G02X82618Y135246I-400J20D01*
G01X79263Y138602D01*
X58998D01*
G03X55533Y136140I-1398J-1701D01*
G02X55158Y135602I-375J-138D01*
G01X32602D01*
G37*
G36*
G01X186000Y64000D02*
X183500Y66500D01*
X181852D01*
G03X179288Y67842I-2052J-800D01*
G02X179046Y67991I-47J194D01*
G03X174757Y66992I-2146J-491D01*
G02X174368Y66500I-389J-92D01*
G01X169858D01*
G02X169496Y67069I0J400D01*
G03X165354Y67506I-1996J931D01*
G02X164816Y67045I-390J-89D01*
G03X162388Y66500I-816J-2045D01*
G01X155441D01*
G02X155066Y67038I0J400D01*
G03X150934I-2066J762D01*
G02X150559Y66500I-375J-138D01*
G01X147467D01*
G02X147082Y67008I0J400D01*
G03X140918I-3082J867D01*
G02X140533Y66500I-385J-108D01*
G01X114000D01*
X113401Y67099D01*
X113402Y67183D01*
G03X111183Y69402I-2202J17D01*
G01X111099Y69401D01*
X108500Y72000D01*
Y99000D01*
X102500Y105000D01*
Y116500D01*
X104000Y118000D01*
X125000D01*
X127500Y115500D01*
Y88558D01*
G02X126931Y88196I-400J0D01*
G03X126806Y84151I-931J-1996D01*
G02X127313Y83951I146J-372D01*
G03X130021Y82819I1987J949D01*
G01X130140Y82860D01*
X133000Y80000D01*
X159500D01*
X161500Y78000D01*
X175794D01*
X179495Y74298D01*
X200417D01*
X208725Y82607D01*
G02X209406Y82289I283J-283D01*
G03X213503Y83208I2194J-189D01*
G02X213611Y83731I346J201D01*
G03X214259Y84494I-1310J1770D01*
G01X226675D01*
G02X227038Y83926I0J-400D01*
G03X231034I1998J-926D01*
G02X231397Y84494I363J168D01*
G01X239501D01*
X239506Y84500D01*
X242667D01*
X242717Y84375D01*
G03X246801I2042J825D01*
G01X246851Y84500D01*
X248000D01*
X250250Y82250D01*
X296750D01*
X297500Y81500D01*
X297748D01*
G03X301852I2052J800D01*
G01X307277D01*
X307324Y81367D01*
G03X309742Y79925I2076J733D01*
G02X310203Y79556I62J-395D01*
G03X314256Y80885I2197J144D01*
G02X314593Y81500I337J215D01*
G01X336000D01*
X338099Y83598D01*
X351879D01*
X364498Y70979D01*
Y68700D01*
G03X364500Y68622I2202J17D01*
G01Y68500D01*
X362500Y66500D01*
X342631D01*
G02X342232Y66932I0J400D01*
G03X337044I-2594J206D01*
G02X336645Y66500I-399J-32D01*
G01X297487D01*
X297454Y66658D01*
G03X293146I-2154J-458D01*
G01X293113Y66500D01*
X260841D01*
G03X255959I-2441J-900D01*
G01X242885D01*
G02X242487Y66946I-1J400D01*
G03X238113I-2187J254D01*
G02X237715Y66500I-397J-46D01*
G01X232207D01*
X232185Y66675D01*
G03X227815I-2185J-275D01*
G01X227793Y66500D01*
X222321D01*
G03X220479I-921J-2000D01*
G01X217521D01*
G02X217125Y66953I0J400D01*
G03X212759I-2183J289D01*
G02X212363Y66500I-396J-53D01*
G01X205500D01*
X203000Y64000D01*
X198627D01*
G03X194973I-1827J-1400D01*
G01X186000D01*
G37*
G36*
G01X120000Y151000D02*
X113000Y158000D01*
Y160000D01*
X114000Y161000D01*
X121500D01*
X125500Y157000D01*
X125799D01*
X125853Y156958D01*
G03X128600Y157000I1347J1742D01*
G01X131187D01*
G03X134213I1513J1600D01*
G01X136187D01*
G03X138413I1113J1900D01*
G01X139687D01*
G03X141913I1113J1900D01*
G01X143387D01*
G03X145613I1113J1900D01*
G01X149684D01*
G03X152951Y158408I1120J1896D01*
G01X152964Y158464D01*
X154118Y159618D01*
X158500D01*
G03X160702Y161820I0J2202D01*
G01Y162202D01*
X161000Y162500D01*
Y166089D01*
X162000Y167088D01*
Y179492D01*
X165598Y183090D01*
X167514D01*
G02X167865Y182500I0J-400D01*
G03X171735I1935J-1052D01*
G02X172086Y183090I351J190D01*
G01X182404D01*
X185998Y179496D01*
Y178830D01*
X191505Y173324D01*
X191559D01*
X194500Y170383D01*
Y161000D01*
X193500Y160000D01*
X190000D01*
X183117Y166883D01*
X183143Y166992D01*
G03X183000Y168421I-2143J507D01*
G01Y173500D01*
X179000Y177500D01*
X177668D01*
G03X174288Y176322I-1268J-1800D01*
G01X174273Y176273D01*
X174000Y176000D01*
X167000D01*
X166000Y175000D01*
Y174835D01*
X165957Y174780D01*
G03X166000Y172848I1183J-940D01*
G01Y165617D01*
G03X165948Y162606I1581J-1533D01*
G01X166000Y162549D01*
Y162197D01*
X165950Y162140D01*
G03Y159228I1652J-1456D01*
G01X166000Y159171D01*
Y158500D01*
X162852Y155352D01*
X161594D01*
X160742Y154500D01*
X156000D01*
X155876Y154376D01*
X155283D01*
X151910Y151004D01*
X147670D01*
X146797Y151876D01*
X141730D01*
X140853Y151000D01*
X132421D01*
G03X130579I-921J-2000D01*
G01X120000D01*
G37*
G36*
G01X131079Y164655D02*
G03X126689Y166868I-2579J345D01*
G02X126128Y166872I-278J287D01*
G01X112000Y181000D01*
Y183000D01*
X113000Y184000D01*
X132500D01*
X134500Y186000D01*
X157000D01*
X158500Y184500D01*
Y182219D01*
X157596Y181316D01*
Y169096D01*
X155000Y166500D01*
X148500D01*
X147898Y165898D01*
X147797D01*
X146101Y164202D01*
X131475D01*
G02X131079Y164655I0J400D01*
G37*
G36*
G01X164000Y97000D02*
X170112Y90888D01*
X170127Y90846D01*
G03X171454Y89519I2072J745D01*
G01X171496Y89504D01*
X172000Y89000D01*
X176330D01*
X176832Y88498D01*
X191000D01*
Y86906D01*
X189544Y85450D01*
X179856D01*
X179305Y86002D01*
X166448D01*
X161950Y90500D01*
X152550D01*
X152502Y90452D01*
X141448D01*
X138795Y93105D01*
X138799Y93193D01*
G03X134754Y94500I-2199J107D01*
G01X133000D01*
X132000Y95500D01*
Y98000D01*
X133000Y99000D01*
X148899D01*
X148935Y98845D01*
G03X151252Y97149I2145J499D01*
G01X151344Y97156D01*
X151500Y97000D01*
X155903D01*
Y96798D01*
G03X160307I2202J-23D01*
G01Y97000D01*
X164000D01*
G37*
G36*
G01X226856Y131500D02*
X222726Y135630D01*
Y144238D01*
X208138Y158826D01*
X197174D01*
X196100Y159900D01*
Y167400D01*
X197500Y168800D01*
X199800D01*
X203600Y165000D01*
X211000D01*
X224500Y151500D01*
Y148319D01*
G03X225749Y145213I1952J-1019D01*
G01X225793Y145198D01*
X225967Y145024D01*
X225798Y144855D01*
Y139700D01*
G03X226000Y138780I2202J1D01*
G01Y137500D01*
X229000Y134500D01*
Y132500D01*
X228000Y131500D01*
X226856D01*
G37*
G36*
G01X325781Y166000D02*
G02X325381Y166396I0J400D01*
G03X323669Y167687I-1352J-12D01*
G01X323557Y167656D01*
X314000Y177213D01*
Y181262D01*
X314023Y181306D01*
G03X313326Y183197I-1194J634D01*
G01X313287Y183213D01*
X313000Y183500D01*
Y187284D01*
G03X312151Y189399I-1100J786D01*
G01X312090Y189410D01*
X312000Y189500D01*
X304778D01*
X304727Y189623D01*
G03X303619Y190445I-1247J-523D01*
G01X303548Y190452D01*
X302639Y191361D01*
X302625Y191412D01*
G03X301672Y192365I-1305J-352D01*
G01X301621Y192379D01*
X301500Y192500D01*
X300552D01*
X279016Y214036D01*
X270341D01*
G03X268901Y213500I0J-2202D01*
G01X260500D01*
X259318Y214682D01*
G03X255136Y215316I-2318J-1182D01*
G02X254564I-286J279D01*
G03X250793Y215270I-1864J-1816D01*
G02X250207I-293J273D01*
G03X246174Y215000I-1907J-1770D01*
G01X238500D01*
X223000Y230500D01*
Y245000D01*
X226000Y248000D01*
X263723D01*
G03X267277I1777J1300D01*
G01X271500D01*
X275000Y251500D01*
X294579D01*
G03X296384Y251483I921J2000D01*
G01X296422Y251500D01*
X297632D01*
G03X300168I1268J1800D01*
G01X301937D01*
X301965Y251492D01*
G03X303235I635J2108D01*
G01X303263Y251500D01*
X305337D01*
X305365Y251492D01*
G03X306635I635J2108D01*
G01X306663Y251500D01*
X308737D01*
X308765Y251492D01*
G03X310035I635J2108D01*
G01X310063Y251500D01*
X365000D01*
X371000Y245500D01*
Y243221D01*
G03Y241379I2000J-921D01*
G01Y239821D01*
G03Y237979I2000J-921D01*
G01Y222500D01*
X369500Y221000D01*
Y220160D01*
X369336Y220130D01*
G03Y217470I244J-1330D01*
G01X369500Y217440D01*
Y216760D01*
X369336Y216730D01*
G03X369812Y214068I244J-1330D01*
G01X369914Y214086D01*
X379000Y205000D01*
Y193392D01*
X378498Y192891D01*
Y189119D01*
X379000Y188618D01*
Y179500D01*
X379048Y179452D01*
Y177869D01*
X379050Y177868D01*
Y176950D01*
X379544Y176456D01*
G03X379626Y176374I996J914D01*
G01X380500Y175500D01*
X384860D01*
G02X385257Y175054I0J-400D01*
G03X387943I1343J-154D01*
G02X388340Y175500I397J46D01*
G01X388806D01*
Y175258D01*
X388789Y175219D01*
G03X391241Y174081I1236J-547D01*
G02X391939Y174118I359J-175D01*
G03X394250Y174150I1146J718D01*
G02X394818Y174279I345J-203D01*
G03X396922Y175313I755J1121D01*
G01X396934Y175500D01*
X401000D01*
X401353Y175147D01*
X401315Y175031D01*
G03X401791Y173527I1285J-421D01*
G02X401778Y172877I-239J-320D01*
G03X403889Y171672I762J-1117D01*
G02X404571Y171929I399J-26D01*
G01X406204Y170296D01*
X406214Y170230D01*
G03X406500Y169575I1338J194D01*
G01Y168641D01*
G03Y166217I600J-1212D01*
G01Y164412D01*
G02X406077Y164013I-400J0D01*
G03X406451Y161388I-76J-1350D01*
G01X406570Y161430D01*
X407000Y161000D01*
X414500D01*
X419500Y156000D01*
X420860D01*
G02X421203Y155395I0J-400D01*
G03X423523I1160J-695D01*
G02X423866Y156000I343J205D01*
G01X428500D01*
X429500Y155000D01*
X429868D01*
G02X430268Y154605I0J-400D01*
G03X432972I1352J15D01*
G02X433372Y155000I400J-5D01*
G01X440000D01*
X444500Y150500D01*
Y148000D01*
X443500Y147000D01*
X439000D01*
X438000Y148000D01*
X428000D01*
X427500Y148500D01*
X422426D01*
G02X422069Y149080I0J400D01*
G03X419653I-1208J607D01*
G02X419296Y148500I-357J-180D01*
G01X416603D01*
G02X416260Y149105I0J400D01*
G03X413940I-1160J695D01*
G02X413597Y148500I-343J-205D01*
G01X410335D01*
G02X409993Y149107I0J400D01*
G03X407681I-1156J702D01*
G02X407339Y148500I-342J-207D01*
G01X405500D01*
X404500Y147500D01*
Y146500D01*
X403635Y145635D01*
X403520Y145669D01*
G03X401837Y143986I-388J-1295D01*
G01X401871Y143871D01*
X399592Y141592D01*
X399492Y141606D01*
G03X398777Y141515I-193J-1338D01*
G01X398740Y141500D01*
X396706D01*
X396669Y141515D01*
G03X395627I-521J-1247D01*
G01X395590Y141500D01*
X393558D01*
X393521Y141515D01*
G03X391648Y140236I-521J-1247D01*
G01X391650Y140150D01*
X391500Y140000D01*
X375558D01*
X375551Y140193D01*
G03X373333Y141182I-1351J-49D01*
G02X372794Y141206I-256J307D01*
G01X369500Y144500D01*
Y153000D01*
X368500Y154000D01*
X366000D01*
X362413Y157587D01*
X362838Y158012D01*
G03X360362Y160488I-1238J1238D01*
G01X360062Y160189D01*
G02X359482Y160204I-283J283D01*
G03X359332Y160348I-1009J-901D01*
G02X359354Y160985I253J310D01*
G03X357721Y161042I-779J1105D01*
G02X357699Y160405I-253J-310D01*
G03X357285Y159937I778J-1105D01*
G01X357228Y159832D01*
X354030D01*
X353500Y159302D01*
X350699D01*
X349736Y160264D01*
G02X349718Y160810I283J283D01*
G03X347620Y162513I-1018J890D01*
G02X346980I-320J240D01*
G03X344548Y161700I-1080J-813D01*
G02X344348Y161500I-200J0D01*
G01X344078D01*
X344065Y161686D01*
G03X342650Y162943I-1349J-93D01*
G01X342561Y162939D01*
X341099Y164401D01*
Y164483D01*
G03X339752Y165830I-1352J-5D01*
G01X339670D01*
X339500Y166000D01*
X335010D01*
X334974Y166014D01*
G03X333966I-504J-1254D01*
G01X333930Y166000D01*
X325781D01*
G37*
G36*
G01X320526Y124000D02*
G03X320137Y124370I-1108J-775D01*
G01X320118Y124382D01*
X314500Y130000D01*
Y134500D01*
X307000Y142000D01*
Y149000D01*
X306064Y149936D01*
G02X306059Y150213I141J141D01*
G03X305050Y152526I-1009J936D01*
G01X304620D01*
X301750Y155397D01*
Y156750D01*
X298492Y160008D01*
X298499Y160098D01*
G03X296898Y161699I-1499J102D01*
G01X296808Y161692D01*
X296407Y162093D01*
X296637Y162323D01*
X296756Y162282D01*
G03X295748Y163714I494J1418D01*
G02X295065Y163435I-400J4D01*
G01X289000Y169500D01*
X277500D01*
X263000Y184000D01*
Y186900D01*
G03X263388Y189000I-1700J1400D01*
G02X263603Y189492I379J127D01*
G03X264322Y190011I-903J2008D01*
G02X264851Y190065I295J-270D01*
G03X264518Y193339I1289J1785D01*
G02X263989Y193285I-295J270D01*
G03X262547Y193697I-1290J-1785D01*
G01X262456Y193690D01*
X260070Y196076D01*
X259424D01*
X258000Y197500D01*
X248735D01*
G03X245917Y198749I-2046J-813D01*
G01X245796Y198704D01*
X245000Y199500D01*
Y205000D01*
X246000Y206000D01*
X280826D01*
X295847Y190978D01*
G02X295782Y190360I-283J-283D01*
G03X296599Y187598I818J-1260D01*
G02X296798Y187398I-1J-200D01*
G01Y180226D01*
X301126Y175898D01*
X305101D01*
X305410Y175590D01*
X305209Y175388D01*
X305123Y175390D01*
G03X304112Y175027I-31J-1502D01*
G02X303586Y175031I-261J303D01*
G03X303570Y172767I-995J-1125D01*
G02X304096Y172763I261J-303D01*
G03X304794Y172416I995J1125D01*
G02X305114Y171994I-79J-392D01*
G03X307634Y170782I1498J-112D01*
G02X308160Y170798I272J-293D01*
G03X310006Y170753I952J1162D01*
G01X310144Y170856D01*
X314047Y166953D01*
X314038Y166860D01*
G03X315511Y165387I1346J-127D01*
G01X315604Y165396D01*
X318361Y162639D01*
X318371Y162577D01*
G03X319477Y161471I1333J227D01*
G01X319539Y161461D01*
X320569Y160431D01*
X320584Y160390D01*
G03X321890Y159084I2066J760D01*
G01X321931Y159069D01*
X322882Y158118D01*
X322866Y158017D01*
G03X324417Y156466I1334J-217D01*
G01X324518Y156482D01*
X325500Y155500D01*
Y155104D01*
G03X326955Y152825I734J-1135D01*
G01X327090Y152910D01*
X328588Y151412D01*
X328540Y151291D01*
G03X328449Y150745I1260J-491D01*
G02X327899Y150359I-399J-16D01*
G03X326528Y150148I-509J-1253D01*
G02X326246Y150175I-128J154D01*
G03X323913Y148905I-1046J-856D01*
G02X323479Y148386I-381J-123D01*
G03X324587Y147460I-179J-1340D01*
G02X325021Y147979I381J123D01*
G03X326062Y148277I180J1340D01*
G02X326344Y148250I128J-154D01*
G03X326822Y147879I1047J855D01*
G02X326892Y147195I-168J-363D01*
G03X328915Y145523I804J-1087D01*
G02X329623Y145549I361J-173D01*
G03X331870Y145400I1173J672D01*
G02X332544Y145338I317J-243D01*
G03X332676Y146771I1206J611D01*
G02X332002Y146833I-317J243D01*
G03X329577Y146806I-1206J-612D01*
G02X328869Y146780I-361J173D01*
G03X328264Y147335I-1173J-672D01*
G02X328194Y148019I168J363D01*
G03X328741Y149161I-804J1087D01*
G02X329291Y149547I399J16D01*
G03X330758Y149846I509J1253D01*
G02X331042I142J-141D01*
G03X333090Y150000I958J954D01*
G01X334441D01*
G03X336792Y150732I1009J900D01*
G01X336800Y150800D01*
X338448Y152448D01*
X338522Y152454D01*
G03X338761Y152494I-103J1348D01*
G01X338786Y152500D01*
X343928D01*
X343953Y152493D01*
G03X345634Y153581I347J1307D01*
G01X345645Y153645D01*
X346000Y154000D01*
X348828D01*
G02X349221Y153527I0J-400D01*
G03X351879I1329J-247D01*
G02X352272Y154000I393J73D01*
G01X353794D01*
G02X354161Y153440I0J-400D01*
G03X356639I1239J-540D01*
G02X357006Y154000I367J160D01*
G01X362000D01*
X363347Y152653D01*
X363354Y152581D01*
G03X364568Y151367I1346J132D01*
G01X364640Y151360D01*
X366761Y149239D01*
X366776Y149202D01*
G03X367000Y148838I1249J518D01*
G01Y147410D01*
G03X367781Y145166I1000J-910D01*
G01X367845Y145155D01*
X369000Y144000D01*
Y133500D01*
X367000Y131500D01*
X355500D01*
X353889Y129889D01*
X353846Y129874D01*
G03X353026Y129054I454J-1274D01*
G01X353011Y129011D01*
X351500Y127500D01*
X350690D01*
G03X348510I-1090J-800D01*
G01X345000D01*
X344439Y128061D01*
X344463Y128169D01*
G03X342064Y127662I-1317J304D01*
G02X342031Y127143I-320J-240D01*
G03X341697Y125840I969J-943D01*
G01X341728Y125728D01*
X341000Y125000D01*
X334000D01*
X332347Y126653D01*
G03X332141Y126861I-1058J-842D01*
G01X332133Y126867D01*
X332000Y127000D01*
X331933D01*
X331891Y127021D01*
G03X330689I-601J-1211D01*
G01X330647Y127000D01*
X329500D01*
X329263Y126763D01*
X329169Y126773D01*
G03X327686Y125290I-138J-1345D01*
G01X327696Y125196D01*
X326500Y124000D01*
X320526D01*
G37*
G36*
G01X284000Y164500D02*
X292500Y156000D01*
X297000D01*
X299500Y153500D01*
Y143753D01*
G03X299477Y141977I1200J-904D01*
G01X297500Y140000D01*
X280500D01*
X279832Y140668D01*
X279908Y140801D01*
G03X278498Y144045I-1908J1099D01*
G01X278442Y144058D01*
X275500Y147000D01*
Y154685D01*
G03Y157711I-1600J1513D01*
G01Y161601D01*
G03X276273Y163655I-1400J1699D01*
G01X276256Y163756D01*
X277000Y164500D01*
X284000D01*
G37*
G36*
G01X465749Y3001D02*
X464750Y4000D01*
Y7250D01*
X470000Y12500D01*
X499500D01*
X502000Y10000D01*
X684000D01*
X684753Y10753D01*
X684830Y10756D01*
G03X686004Y11415I-70J1500D01*
G01X693237Y22109D01*
G02X693902Y22106I331J-224D01*
G03X695214Y24192I1127J747D01*
G02X694893Y24727I54J396D01*
G01X695575Y26575D01*
X696500Y27500D01*
Y29080D01*
X697002Y30439D01*
Y34683D01*
X696500Y36793D01*
Y48000D01*
X651000Y93500D01*
Y101000D01*
X629000Y123000D01*
X623226D01*
G02X622899Y123631I0J400D01*
G03X619301I-1799J1269D01*
G02X618974Y123000I-327J-231D01*
G01X614500D01*
X609000Y128500D01*
X589000D01*
X584500Y124000D01*
X472500D01*
X463906Y132594D01*
X464048Y132736D01*
Y132737D01*
G03X462137Y134648I-948J963D01*
G01X462136D01*
X461994Y134506D01*
X461500Y135000D01*
X453500D01*
X451000Y132500D01*
X437500D01*
X436701Y131702D01*
X433299D01*
X431000Y134000D01*
Y139500D01*
X432500Y141000D01*
Y146000D01*
X433500Y147000D01*
X438000D01*
X439500Y145500D01*
X444500D01*
X446000Y147000D01*
Y157500D01*
X446783Y158283D01*
X447516Y158498D01*
X608566D01*
X608572Y158500D01*
X615100D01*
X630350Y143250D01*
X645750D01*
X673000Y116000D01*
X680346D01*
G02X680693Y115400I0J-400D01*
G03X684507I1907J-1100D01*
G02X684854Y116000I347J200D01*
G01X696779D01*
G02X697157Y115471I0J-400D01*
G03X701325I2084J-712D01*
G02X701703Y116000I378J129D01*
G01X735379D01*
G03X737221I921J2000D01*
G01X742010D01*
G03X742190I90J2200D01*
G01X746398D01*
G02X746598Y115800I0J-200D01*
G03X751002I2202J0D01*
G02X751210Y116000I200J0D01*
G03X751390I90J2200D01*
G01X751447D01*
G02X751839Y115523I0J-400D01*
G03X756161Y115522I2161J-423D01*
G02X756554Y115998I393J76D01*
G01X771002D01*
X787000Y100000D01*
Y95558D01*
X786850Y95519D01*
G03X785550Y94723I649J-2520D01*
G02X784950I-300J264D01*
G03Y91277I-1950J-1723D01*
G02X785550I300J-264D01*
G03X786850Y90481I1949J1724D01*
G01X787000Y90442D01*
Y80000D01*
X789500Y77500D01*
X819000D01*
X823500Y73000D01*
Y4000D01*
X822501Y3001D01*
X465749D01*
G37*
G36*
G01X588000Y236500D02*
X587002Y237498D01*
Y250471D01*
G02X587456Y250867I400J0D01*
G03X588298Y253388I186J1339D01*
G02X588312Y254094I195J349D01*
G03X587470Y256632I-612J1206D01*
G02X587002Y257026I-68J394D01*
G01Y268002D01*
X588003Y269003D01*
X588110Y268979D01*
G03X589490Y269500I290J1321D01*
G01X590288D01*
G03X592811Y269771I1212J600D01*
G01X592825Y269825D01*
X594000Y271000D01*
Y273500D01*
X594788Y274288D01*
X603575D01*
G02X603915Y273678I0J-400D01*
G03X604301Y271851I1150J-711D01*
G02X604309Y271197I-226J-330D01*
G03X605864Y271216I791J-1097D01*
G02X605856Y271870I226J330D01*
G03X606215Y273678I-791J1097D01*
G02X606555Y274288I340J210D01*
G01X608457D01*
G02X608786Y273660I0J-400D01*
G03X608793Y272107I1110J-772D01*
G02X608587Y271495I-327J-231D01*
G03X610099Y270988I409J-1289D01*
G02X610305Y271600I327J231D01*
G03X611006Y273660I-409J1289D01*
G02X611335Y274288I329J228D01*
G01X635861D01*
G02X636198Y273673I0J-400D01*
G03X636529Y271860I1139J-729D01*
G02X636518Y271211I-239J-321D01*
G03X638096Y271184I770J-1111D01*
G02X638107Y271833I239J321D01*
G03X638476Y273673I-770J1111D01*
G02X638813Y274288I337J215D01*
G01X641378D01*
G02X641734Y273706I0J-400D01*
G03X642689Y271760I1203J-617D01*
G02X642952Y271151I-73J-393D01*
G03X645377Y270007I1138J-731D01*
G02X645896Y270260I381J-122D01*
G03X647708Y271428I464J1270D01*
G02X648149Y271795I399J-31D01*
G03X649513Y273718I142J1345D01*
G02X649875Y274288I362J170D01*
G01X651538D01*
G02X651881Y273683I0J-400D01*
G03X654201I1160J-694D01*
G02X654544Y274288I343J205D01*
G01X655812D01*
X663500Y266600D01*
Y261000D01*
X655332Y252832D01*
G02X654718Y252890I-283J283D01*
G03X652840Y251012I-1118J-760D01*
G02X652898Y250398I-225J-331D01*
G01X639000Y236500D01*
X588000D01*
G37*
G36*
G01X618304Y11500D02*
G02X617915Y11993I0J400D01*
G03X615279Y12593I-1315J314D01*
G02X614605Y12395I-391J85D01*
G01X613500Y13500D01*
Y29416D01*
G02X614175Y29707I400J0D01*
G03Y31673I928J983D01*
G02X613500Y31964I-275J291D01*
G01Y41000D01*
X623500Y51000D01*
X656500D01*
X660000Y47500D01*
Y27648D01*
G02X659554Y27250I-400J-1D01*
G03Y24564I-154J-1343D01*
G02X660000Y24166I46J-397D01*
G01Y22215D01*
G02X659554Y21817I-400J-1D01*
G03Y19131I-154J-1343D01*
G02X660000Y18733I46J-397D01*
G01Y13000D01*
X658500Y11500D01*
X651000D01*
X650500Y12000D01*
Y15000D01*
X649722Y15778D01*
X649708Y15830D01*
G03X647501Y16500I-1308J-340D01*
G01X646218D01*
G03X644085Y16101I-918J-993D01*
G01X644071Y16071D01*
X643000Y15000D01*
Y13545D01*
X642980Y13503D01*
G03Y12311I1213J-596D01*
G01X643000Y12269D01*
Y12000D01*
X642500Y11500D01*
X618304D01*
G37*
G36*
G01X751524Y241970D02*
X736124Y226570D01*
Y218030D01*
X737610Y216544D01*
X737603Y216453D01*
G03X738214Y214772I2197J-153D01*
G02X738229Y214234I-288J-277D01*
G03X740410Y210658I1671J-1434D01*
G02X740887Y210381I93J-389D01*
G03X745199Y210880I2113J619D01*
G01X745203Y210956D01*
X746976Y212730D01*
Y218021D01*
X745426Y219572D01*
G02X745461Y220169I283J283D01*
G03X746143Y221077I-1360J1732D01*
G01X746158Y221115D01*
X759543Y234500D01*
X761000D01*
X762310Y233190D01*
Y219457D01*
X753130Y210276D01*
X746779D01*
X723002Y186500D01*
X716600D01*
X708750Y194350D01*
Y210250D01*
X724870Y226370D01*
G02X725499Y226289I283J-282D01*
G03X728511Y229301I1901J1111D01*
G02X728430Y229930I201J346D01*
G01X729500Y231000D01*
Y240760D01*
X730202Y245182D01*
Y253631D01*
X730135Y254011D01*
X730351Y254049D01*
X730371Y254048D01*
G03X730088Y256716I28J1352D01*
G02X729602Y257035I-92J389D01*
G01X729500Y257613D01*
Y269500D01*
X727000Y272000D01*
Y273500D01*
X727500Y274000D01*
X728500D01*
X729000Y273500D01*
Y272000D01*
X729500Y271500D01*
X730331D01*
G03X730469I69J1350D01*
G01X731500D01*
X734000Y274000D01*
X734500D01*
X747624Y260876D01*
Y255544D01*
X751524Y251644D01*
Y241970D01*
G37*
G36*
G01X755870Y204024D02*
X768464Y216617D01*
Y237964D01*
X768500Y238000D01*
Y286000D01*
X770000Y287500D01*
X822500D01*
X823500Y286500D01*
Y271500D01*
X823000Y271000D01*
X822000D01*
X818492Y274508D01*
G02X818586Y275144I282J283D01*
G03X810540Y280675I-2586J4856D01*
G01X810518Y280500D01*
X807000D01*
X805750Y279250D01*
Y262750D01*
X811500Y257000D01*
Y190500D01*
X811000Y190000D01*
X809000D01*
X806500Y192500D01*
Y256500D01*
X802000Y261000D01*
Y265000D01*
X796000Y271000D01*
X785500D01*
X775500Y261000D01*
Y158000D01*
X772500Y155000D01*
X724000D01*
X722500Y156500D01*
Y173899D01*
G02X723131Y174226I400J0D01*
G03X726114Y174642I1270J1799D01*
G02X726636Y174731I311J-251D01*
G03X726086Y177983I1164J1869D01*
G02X725564Y177894I-311J251D01*
G03X724635Y178214I-1163J-1869D01*
G02X724395Y178895I43J398D01*
G01X736000Y190500D01*
Y190794D01*
X740306Y195101D01*
G02X740975Y194923I283J-283D01*
G03X743677Y197625I2125J577D01*
G02X743499Y198294I105J386D01*
G01X749229Y204024D01*
X755870D01*
G37*
G36*
G01X788000Y186000D02*
X780500D01*
X778500Y188000D01*
Y217000D01*
X780500Y219000D01*
X787000D01*
X788500Y220500D01*
X802000D01*
X804500Y218000D01*
Y188500D01*
X801000Y185000D01*
X789000D01*
X788000Y186000D01*
G37*
G36*
G01X787000Y222000D02*
X785500Y220500D01*
X780000D01*
X778000Y222500D01*
Y261000D01*
X786500Y269500D01*
X794500D01*
X800000Y264000D01*
Y260500D01*
X805000Y255500D01*
Y223500D01*
X803500Y222000D01*
X787000D01*
G37*
G36*
G01X823500Y104000D02*
X799500Y80000D01*
X791500D01*
X789500Y82000D01*
Y88000D01*
X797863Y96363D01*
X797993Y96295D01*
G03X801505Y99807I1207J2305D01*
G01X801437Y99937D01*
X813000Y111500D01*
Y128860D01*
G03Y131140I-2000J1140D01*
G01Y132860D01*
G03Y135140I-2000J1140D01*
G01Y136860D01*
G03X813024Y139096I-2000J1140D01*
G01X813000Y139141D01*
Y140165D01*
G03Y143035I-1800J1435D01*
G01Y191578D01*
X813007Y191604D01*
G03Y192996I-2507J696D01*
G01X813000Y193022D01*
Y195778D01*
X813007Y195804D01*
G03Y197196I-2507J696D01*
G01X813000Y197222D01*
Y257500D01*
X807500Y263000D01*
Y277500D01*
X808500Y278500D01*
X810707D01*
G03X816390Y274512I5293J1500D01*
G01X816481Y274519D01*
X823500Y267500D01*
Y104000D01*
G37*
%LPC*%
G75*
G36*
G01X15440Y107333D02*
G03Y106667I222J-333D01*
G02X12560I-1440J-2167D01*
G03Y107333I-222J333D01*
G02X15440I1440J2167D01*
G37*
G36*
G01X94006Y60889D02*
G03X93823Y61105I-199J17D01*
G02X92487Y61700I177J2195D01*
G03X92204Y61692I-138J-145D01*
G02X92113Y64800I-1604J1508D01*
G03X92396Y64808I138J145D01*
G02X96194Y63111I1604J-1508D01*
G03X96377Y62895I199J-17D01*
G02X94006Y60889I-177J-2195D01*
G37*
G36*
G01X117000Y58912D02*
X119201D01*
G02X119210Y58911I-161J-1494D01*
G03X119393Y59194I1J200D01*
G02X121153Y57912I2007J906D01*
G03X120709Y57491I-45J-397D01*
G02X120712Y57410I-1509J-96D01*
G01Y57315D01*
X120702Y57231D01*
G02X119200Y55888I-1502J168D01*
G01X115800D01*
G02X114429Y58036I0J1512D01*
G03X114179Y58587I-363J167D01*
G02X116662Y59525I621J2113D01*
G03X117000Y58912I338J-213D01*
G37*
G36*
G01X132660D02*
X134140D01*
G03X134487Y59510I0J400D01*
G02X138600Y60508I1913J1090D01*
G03X138934Y60096I400J-17D01*
G02X136864Y56537I-360J-2172D01*
G03X136228Y56519I-311J-252D01*
G02X135000Y55888I-1229J881D01*
G01X131600D01*
G02X130183Y57927I0J1512D01*
G03X129899Y58456I-375J140D01*
G02X132313Y59510I501J2144D01*
G03X132660Y58912I347J-198D01*
G37*
G36*
G01X309140Y58584D02*
G03X309728Y58685I249J313D01*
G02X309817Y56227I1870J-1163D01*
G03X309223Y56287I-324J-235D01*
G02X308200Y55888I-1023J1112D01*
G01X304799D01*
G02X303330Y57048I1J1512D01*
G03X302858Y57346I-389J-93D01*
G02X304573Y59144I-458J2154D01*
G03X304774Y58911I197J-33D01*
G02X304800Y58912I71J-1509D01*
G01X308200D01*
G02X309140Y58584I0J-1511D01*
G37*
G36*
G01X286637Y56397D02*
G03X286196Y55969I-42J-397D01*
G02X284777Y57860I-2196J-170D01*
G03X285312Y58165I141J374D01*
G02X286800Y59412I1488J-264D01*
G01X290200D01*
G02X290261Y59410I-19J-1511D01*
G03X290455Y59684I8J200D01*
G02X292171Y58323I2045J816D01*
G03X291711Y57922I-60J-396D01*
G02X291712Y57910I-1502J-131D01*
G01Y57815D01*
X291702Y57731D01*
G02X290200Y56388I-1502J168D01*
G01X286799D01*
G02X286637Y56397I3J1512D01*
G37*
G36*
G01X272431Y57986D02*
G03X272993Y57758I379J128D01*
G02X271803Y55657I1007J-1958D01*
G03X271319Y56023I-399J-25D01*
G02X271000Y55988I-323J1477D01*
G01X267999D01*
G02X268000Y59012I1J1512D01*
G01X271000D01*
G02X272431Y57986I0J-1511D01*
G37*
G36*
G01X324682Y56412D02*
X326100D01*
G03X326438Y57025I0J400D01*
G02X328995Y56111I1862J1175D01*
G03X328761Y55557I126J-380D01*
G02X328912Y54910I-1361J-659D01*
G01Y54815D01*
X328902Y54731D01*
G02X327400Y53388I-1502J168D01*
G01X323999D01*
G02X322632Y55543I1J1512D01*
G03X322313Y56111I-362J170D01*
G02X321075Y56663I234J2189D01*
G03X320471Y56582I-268J-297D01*
G02X319200Y55888I-1271J817D01*
G01X315800D01*
G02Y58912I0J1512D01*
G01X319201D01*
G02X319890Y58745I-2J-1512D01*
G03X320453Y58978I182J356D01*
G02X324354Y57040I2095J-678D01*
G03X324682Y56412I328J-228D01*
G37*
G36*
G01X100050Y55912D02*
X102200D01*
G03X102538Y56525I0J400D01*
G02X105058Y55599I1862J1175D01*
G03X104816Y55046I120J-382D01*
G02X104962Y54410I-1365J-648D01*
G01Y54315D01*
X104952Y54231D01*
G02X103450Y52888I-1502J168D01*
G01X100050D01*
G02X99469Y53005I2J1512D01*
G03X98929Y52737I-153J-370D01*
G02X98150Y55040I-2129J563D01*
G03X98741Y55156I245J316D01*
G02X100050Y55912I1309J-755D01*
G37*
G36*
G01X314124Y51148D02*
G03X314562Y50814I395J64D01*
G02X312626Y48277I238J-2189D01*
G03X312188Y48611I-395J-64D01*
G02X314124Y51148I-238J2189D01*
G37*
G36*
G01X329725Y46936D02*
G03X329152I-286J-279D01*
G02X325961Y46979I-1575J1539D01*
G03X325678Y46990I-147J-136D01*
G02X322578Y47085I-1502J1610D01*
G03X321998I-290J-275D01*
G02Y50115I-1598J1515D01*
G03X322578I290J275D01*
G02X325792Y50096I1598J-1515D01*
G03X326075Y50085I147J136D01*
G02X329152Y50014I1502J-1610D01*
G03X329725I286J279D01*
G02Y46936I1575J-1539D01*
G37*
G36*
G01X25900Y79742D02*
G02X22714Y78542I-899J-2442D01*
G03X22500Y79108I-352J191D01*
G02X25794Y82570I900J2442D01*
G03X26506Y82523I368J157D01*
G02X26442Y80393I1894J-1123D01*
G03X25728Y80388I-356J-183D01*
G02X25686Y80308I-2324J1169D01*
G03X25900Y79742I352J-191D01*
G37*
G36*
G01X261964Y56298D02*
X259036D01*
G02X257513Y57590I-36J1502D01*
G03X256924Y57884I-396J-56D01*
G02X255535Y57853I-724J1316D01*
G03X254967Y57580I-177J-359D01*
G02X253464Y56398I-1468J320D01*
G01X250536D01*
G02X249011Y57702I-36J1502D01*
G03X248443Y58010I-396J-53D01*
G02X249692Y59795I-943J1990D01*
G03X250177Y59367I398J-37D01*
G02X250536Y59402I324J-1467D01*
G01X253464D01*
G02X254165Y59247I36J-1502D01*
G03X254733Y59520I177J359D01*
G02X257687Y59410I1467J-321D01*
G03X258276Y59116I396J56D01*
G02X259036Y59302I725J-1316D01*
G01X261964D01*
G02X262633Y59162I35J-1502D01*
G03X263201Y59498I169J362D01*
G02X264067Y58038I1499J-98D01*
G03X263499Y57702I-169J-362D01*
G02X261964Y56298I-1499J98D01*
G37*
G36*
G01X81452Y59468D02*
X79115D01*
G02X77771Y61670I0J1511D01*
G03X77551Y62229I-356J183D01*
G02X77397Y66308I749J2071D01*
G03X77612Y66800I-164J365D01*
G02X80603Y65492I2088J700D01*
G03X80388Y65000I164J-365D01*
G02X80151Y63107I-2088J-700D01*
G03X80487Y62490I336J-217D01*
G01X82886D01*
G02X84396Y60989I-1J-1511D01*
G01Y60894D01*
X84387Y60810D01*
G02X84195Y60225I-1502J169D01*
G03X84397Y59653I347J-199D01*
G02X85513Y56510I-797J-2053D01*
G03X85860Y55912I347J-198D01*
G01X87610D01*
G03X87885Y56602I0J400D01*
G02X89997Y56080I1515J1598D01*
G03X89811Y55424I108J-385D01*
G02X90212Y54410I-1110J-1025D01*
G01Y54315D01*
X90202Y54231D01*
G02X88700Y52888I-1502J168D01*
G01X85299D01*
G02X83865Y54875I1J1512D01*
G03X83503Y55400I-380J125D01*
G02X81782Y58842I97J2200D01*
G03X81452Y59468I-330J226D01*
G37*
G36*
G01X152603Y55394D02*
G02X152651Y53504I2012J-895D01*
G03X151964Y53549I-357J-181D01*
G02X150715Y52888I-1250J851D01*
G01X147315D01*
G02X146196Y53383I0J1512D01*
G03X145562Y53328I-296J-269D01*
G02X142806Y56515I-1862J1175D01*
G03X143005Y57052I-162J366D01*
G02X145889Y55983I1990J943D01*
G03X145690Y55446I162J-366D01*
G02X145742Y55327I-1991J-941D01*
G03X146090Y55285I186J75D01*
G02X147315Y55912I1226J-885D01*
G01X150716D01*
G02X151919Y55314I-1J-1512D01*
G03X152603Y55394I318J242D01*
G37*
G36*
G01X189116Y52798D02*
X187476D01*
G03X187096Y52276I1J-400D01*
G02X184971Y53802I-2096J-676D01*
G03X185365Y54222I-5J400D01*
G02X186901Y55802I1500J78D01*
G01X189664D01*
G02X191169Y54614I36J-1502D01*
G03X191581Y54299I391J84D01*
G02X192630Y54096I119J-2199D01*
G03X193199Y54446I169J363D01*
G02X194736Y55902I1501J-46D01*
G01X197664D01*
G02X198848Y55368I35J-1502D01*
G03X199515Y55453I306J258D01*
G02X203347Y55700I1985J-953D01*
G03X204020Y55705I335J218D01*
G02X205300Y56412I1280J-805D01*
G01X208701D01*
G02X208710Y56411I-161J-1494D01*
G03X208893Y56694I1J200D01*
G02X210653Y55412I2007J906D01*
G03X210209Y54991I-45J-397D01*
G02X210212Y54910I-1509J-96D01*
G01Y54815D01*
X210202Y54731D01*
G02X208700Y53388I-1502J168D01*
G01X205300D01*
G02X204216Y53847I1J1512D01*
G03X203556Y53711I-286J-279D01*
G02X199568Y53444I-2056J789D01*
G03X198898Y53494I-351J-192D01*
G02X197664Y52898I-1198J906D01*
G01X194736D01*
G02X194355Y52938I-35J1502D01*
G03X193869Y52480I-92J-389D01*
G02X189513Y52353I-2169J-380D01*
G03X189116Y52798I-397J45D01*
G37*
G36*
G01X171734Y51112D02*
X173545D01*
G03X173885Y51722I0J400D01*
G02X176986Y54707I1873J1157D01*
G03X177585Y54905I222J332D01*
G02X179036Y55902I1415J-505D01*
G01X181764D01*
G02Y52898I36J-1502D01*
G01X179036D01*
G02X178484Y52989I-36J1502D01*
G03X177949Y52655I-137J-375D01*
G02X175833Y50678I-2191J224D01*
G03X175473Y50137I14J-400D01*
G02X175572Y49610I-1413J-538D01*
G01Y49515D01*
X175562Y49431D01*
G02X174060Y48088I-1502J168D01*
G01X170290D01*
G02X168992Y50374I0J1512D01*
G03X168794Y50951I-344J204D01*
G02X167428Y52641I806J2049D01*
G03X166914Y52957I-395J-66D01*
G02X166463Y52888I-452J1443D01*
G01X163063D01*
G02X162599Y52961I0J1511D01*
G03X162089Y52481I-123J-381D01*
G02X160646Y49841I-2132J-549D01*
G03X160414Y49283I126J-380D01*
G02X160572Y48620I-1354J-673D01*
G01Y48525D01*
X160562Y48441D01*
G02X159060Y47098I-1502J168D01*
G01X155289D01*
G02X155290Y50122I1J1512D01*
G01X157771D01*
G03X158107Y50738I0J400D01*
G02X160974Y53885I1850J1194D01*
G03X161557Y54274I184J355D01*
G02X163063Y55912I1506J127D01*
G01X166464D01*
G02X167838Y55028I-1J-1512D01*
G03X168417Y54857I364J166D01*
G02X171406Y51740I1183J-1857D01*
G03X171734Y51112I328J-228D01*
G37*
G36*
G01X277377Y45512D02*
G02X277338Y44167I1323J-711D01*
G03X276623Y44188I-363J-168D01*
G02X276662Y45533I-1323J711D01*
G03X277377Y45512I363J168D01*
G37*
G36*
G01X39015Y245978D02*
G02X36749Y246020I-1114J1021D01*
G02X36391Y246905I1151J980D01*
G01X36379Y247034D01*
Y247040D01*
X36378D01*
X36479Y250543D01*
X36481Y250546D01*
X36482D01*
X36488Y250551D01*
X36489Y250569D01*
G02X39507Y250632I1511J-69D01*
G01X39512Y250590D01*
Y250460D01*
X39522D01*
X39423Y247008D01*
X39422D01*
Y247002D01*
X39423D01*
X39421Y246954D01*
X39420D01*
X39403Y246831D01*
G02X39015Y245978I-1503J169D01*
G37*
G36*
G01Y231978D02*
G02X36749Y232020I-1114J1021D01*
G02X36391Y232905I1151J980D01*
G01X36379Y233034D01*
Y233040D01*
X36378D01*
X36479Y236543D01*
X36481Y236546D01*
X36482D01*
X36488Y236551D01*
X36489Y236569D01*
G02X39507Y236632I1511J-69D01*
G01X39512Y236590D01*
Y236460D01*
X39522D01*
X39423Y233008D01*
X39422D01*
Y233002D01*
X39423D01*
X39421Y232954D01*
X39420D01*
X39403Y232831D01*
G02X39015Y231978I-1503J169D01*
G37*
G36*
G01X101979Y265710D02*
G03X102072Y265111I304J-259D01*
G02X98721Y264590I-1372J-2211D01*
G03X98628Y265189I-304J259D01*
G02X101979Y265710I1372J2211D01*
G37*
G36*
G01X9112Y264493D02*
Y260628D01*
X9102Y260544D01*
G02X6088Y260713I-1502J169D01*
G01Y264483D01*
G02X9112Y264493I1512J0D01*
G37*
G36*
G01X15102Y258531D02*
Y254666D01*
X15092Y254582D01*
G02X12078Y254751I-1502J169D01*
G01Y258521D01*
G02X15102Y258531I1512J0D01*
G37*
G36*
G01X39412Y257510D02*
Y253915D01*
X39402Y253831D01*
G02X36388Y254000I-1502J169D01*
G01Y257500D01*
G02X39412Y257510I1512J0D01*
G37*
G36*
G01X220169Y253057D02*
G03X219596Y252724I-174J-360D01*
G02X215717Y255164I-2596J176D01*
G03X215744Y255843I-197J348D01*
G02X219797Y258166I1456J2157D01*
G03X220343Y257820I399J26D01*
G02X220169Y253057I957J-2420D01*
G37*
G36*
G01X9112Y252682D02*
Y248817D01*
X9102Y248733D01*
G02X6088Y248902I-1502J169D01*
G01Y252673D01*
G02X9112Y252682I1512J-1D01*
G37*
G36*
G01X71410Y246899D02*
G03X71677Y246799I183J81D01*
G02X73008Y246964I924J-1999D01*
G03X73469Y247256I74J393D01*
G02X77067Y248342I2131J-556D01*
G03X77350Y248359I133J149D01*
G02X80695Y248306I1650J-1459D01*
G03X80978Y248281I154J128D01*
G02X80705Y245194I1422J-1681D01*
G03X80422Y245219I-154J-128D01*
G02X77533Y245258I-1422J1681D01*
G03X77250Y245241I-133J-149D01*
G02X75192Y244536I-1650J1459D01*
G03X74731Y244244I-74J-393D01*
G02X70590Y243901I-2131J556D01*
G03X70323Y244001I-183J-81D01*
G02X71410Y246899I-923J1999D01*
G37*
G36*
G01X15102Y246720D02*
Y242855D01*
X15092Y242771D01*
G02X12078Y242940I-1502J169D01*
G01Y246710D01*
G02X15102Y246720I1512J0D01*
G37*
G36*
G01X39412Y243510D02*
Y239915D01*
X39402Y239831D01*
G02X36388Y240000I-1502J169D01*
G01Y243500D01*
G02X39412Y243510I1512J0D01*
G37*
G36*
G01X9112Y240871D02*
Y237006D01*
X9102Y236922D01*
G02X6088Y237091I-1502J169D01*
G01Y240861D01*
G02X9112Y240871I1512J0D01*
G37*
G36*
G01X14602Y234909D02*
Y231044D01*
X14592Y230960D01*
G02X11578Y231129I-1502J169D01*
G01Y234900D01*
G02X14602Y234909I1512J-1D01*
G37*
G36*
G01X39412Y229510D02*
Y225915D01*
X39402Y225831D01*
G02X36388Y226000I-1502J169D01*
G01Y229500D01*
G02X39412Y229510I1512J0D01*
G37*
G36*
G01X114057Y223592D02*
G03X114041Y222946I228J-329D01*
G02X111443Y223008I-1341J-1746D01*
G03X111459Y223654I-228J329D01*
G02X114057Y223592I1341J1746D01*
G37*
G36*
G01X39412Y222510D02*
Y218915D01*
X39402Y218831D01*
G02X36388Y219000I-1502J169D01*
G01Y222500D01*
G02X39412Y222510I1512J0D01*
G37*
G36*
G01X36302Y212164D02*
Y208336D01*
G02X33298I-1502J-36D01*
G01Y212164D01*
G02X36302I1502J36D01*
G37*
G36*
G01X53372Y191420D02*
Y187555D01*
X53362Y187471D01*
G02X50348Y187640I-1502J169D01*
G01Y191411D01*
G02X53372Y191420I1512J-1D01*
G37*
G36*
G01X59379Y182868D02*
X55719D01*
G02X55720Y185892I1J1512D01*
G01X59379D01*
G02X60890Y184390I0J-1511D01*
G01Y184295D01*
X60881Y184211D01*
G02X59379Y182868I-1502J168D01*
G37*
G36*
G01X8950Y165423D02*
G03X9550I300J264D01*
G02X13119Y161663I1950J-1723D01*
G03Y161037I249J-313D01*
G02X9550Y157277I-1619J-2037D01*
G03X8950I-300J-264D01*
G02X5381Y161037I-1950J1723D01*
G03Y161663I-249J313D01*
G02X8950Y165423I1619J2037D01*
G37*
G36*
G01X31585Y142338D02*
G02X28174Y142787I-1885J-1138D01*
G03X28203Y143332I-278J288D01*
G02X28341Y146820I1997J1668D01*
G03Y147380I-286J280D01*
G02Y151020I1859J1820D01*
G03Y151580I-286J280D01*
G02X28385Y155264I1859J1820D01*
G03X28398Y155824I-279J287D01*
G02X31063Y160088I1902J1776D01*
G03X31556Y160607I117J382D01*
G02X33237Y159012I2444J893D01*
G03X32744Y158493I-117J-382D01*
G02X32115Y155736I-2444J-893D01*
G03X32102Y155176I279J-287D01*
G02X32059Y151580I-1902J-1776D01*
G03Y151020I286J-280D01*
G02Y147380I-1859J-1820D01*
G03Y146820I286J-280D01*
G02X31697Y142872I-1859J-1820D01*
G03X31585Y142338I230J-327D01*
G37*
G36*
G01X152740Y74946D02*
G03X152457I-142J-141D01*
G02X152448Y78057I-1563J1551D01*
G03X152731I141J141D01*
G02X152740Y74946I1563J-1551D01*
G37*
G36*
G01X245042Y72144D02*
G03X244758I-142J-141D01*
G02X241068Y74249I-1558J1556D01*
G03X240607Y74742I-387J100D01*
G02X239367Y74812I-478J2558D01*
G03X238869Y74552I-117J-382D01*
G02X237362Y78517I-3239J1038D01*
G03X237908Y78653I204J344D01*
G02X242581Y76425I2222J-1353D01*
G03X242995Y75892I377J-135D01*
G02X244758Y75256I205J-2192D01*
G03X245042I142J141D01*
G02X248124Y75290I1558J-1556D01*
G03X248693Y75305I277J288D01*
G02X251000Y75888I1607J-1505D01*
G03X251523Y76207I128J379D01*
G02X253000Y73787I2177J-332D01*
G03X252477Y73468I-128J-379D01*
G02X248776Y72210I-2177J332D01*
G03X248207Y72195I-277J-288D01*
G02X245042Y72144I-1607J1505D01*
G37*
G36*
G01X290542Y69544D02*
G03X290258I-142J-141D01*
G02Y72656I-1558J1556D01*
G03X290542I142J141D01*
G02Y69544I1558J-1556D01*
G37*
G36*
G01X191942Y67144D02*
G03X191658I-142J-141D01*
G02Y70256I-1558J1556D01*
G03X191942I142J141D01*
G02X195058I1558J-1556D01*
G03X195342I142J141D01*
G02Y67144I1558J-1556D01*
G03X195058I-142J-141D01*
G02X191942I-1558J1556D01*
G37*
G36*
G01X123466Y77132D02*
G02X119683Y79002I-2171J370D01*
G03X119673Y79285I-146J137D01*
G02X122782Y79400I1497J1615D01*
G03X122792Y79117I146J-137D01*
G02X122926Y78982I-1495J-1617D01*
G03X123616Y79183I296J269D01*
G02X124156Y77333I2171J-370D01*
G03X123466Y77132I-296J-269D01*
G37*
G36*
G01X359860Y210183D02*
Y210136D01*
X359855Y210099D01*
G02X359832Y209943I-1357J120D01*
G03X359994Y209720I198J-27D01*
G02X358422Y208645I-244J-1330D01*
G03X358275Y208876I-196J37D01*
G02X357138Y210146I223J1344D01*
G01X357128Y210145D01*
X357011Y212357D01*
X357012D01*
Y212359D01*
X357021Y212476D01*
G02X358239Y213782I1361J-49D01*
G03X358559Y214157I-80J392D01*
G02X358801Y214873I1351J-58D01*
G03X358711Y215423I-328J229D01*
G01X357551Y216155D01*
G03X357024Y216002I-182J-356D01*
G02X356289Y217972I-1164J688D01*
G03X356758Y218146I126J380D01*
G02X358691Y218669I1208J-630D01*
G01X358696Y218677D01*
X360524Y217524D01*
X360521D01*
X360529Y217518D01*
X360532D01*
X360561Y217500D01*
Y217499D01*
X360571Y217492D01*
X360651Y217426D01*
G02X361189Y216351I-824J-1085D01*
G01X361190D01*
Y216348D01*
X361188D01*
Y216344D01*
X361189D01*
G02X361188Y216277I-1362J-13D01*
G01Y216257D01*
X361185Y216235D01*
G02X360890Y215488I-1358J105D01*
G03X360921Y214998I330J-225D01*
G02X359944Y212748I-1011J-898D01*
G01X359942D01*
X359739Y212738D01*
X359751Y212502D01*
X359752D01*
X359756Y212434D01*
X359755D01*
Y212430D01*
X359756D01*
X359869Y210292D01*
X359866Y210290D01*
X359860Y210284D01*
Y210222D01*
G02Y210183I-1362J-19D01*
G37*
G36*
G01X347922Y208955D02*
G03X347802Y208714I73J-186D01*
G02X346145Y209654I-1302J-364D01*
G03X346287Y209888I-54J193D01*
G02X346233Y210197I1306J387D01*
G01X346222Y210305D01*
Y210318D01*
X346221D01*
X346253Y211297D01*
G03X345773Y211676I-400J-13D01*
G02X344341Y212305I-273J1324D01*
G03X343826Y212460I-343J-206D01*
G02X341881Y213663I-584J1230D01*
G01X341837Y215882D01*
X341836D01*
G02X343648Y217195I1362J28D01*
G03X344127Y217373I132J377D01*
G02X345052Y215371I1173J-673D01*
G03X344579Y214970I-73J-393D01*
G01X344585Y214667D01*
G03X345102Y214292I400J7D01*
G02X346576Y213818I398J-1292D01*
G03X347054Y213694I318J243D01*
G02X349020Y212605I610J-1218D01*
G01X349026Y212564D01*
Y212434D01*
X349036D01*
X348966Y210284D01*
X348965D01*
X348964Y210280D01*
X348966D01*
X348964Y210233D01*
X348962Y210230D01*
X348959D01*
X348951Y210164D01*
G02X347922Y208955I-1358J113D01*
G37*
G36*
G01X315074Y236715D02*
G03X314526I-274J-291D01*
G02Y238685I-926J985D01*
G03X315074I274J291D01*
G02X316034Y239052I927J-985D01*
G01X319066D01*
G02X319987Y238720I33J-1352D01*
G03X320513I263J302D01*
G02Y236680I887J-1020D01*
G03X319987I-263J-302D01*
G02X319066Y236348I-888J1020D01*
G01X316034D01*
G02X315074Y236715I-33J1352D01*
G37*
G36*
G01X332494Y233657D02*
G03X332926Y233258I400J0D01*
G02X331684Y231911I110J-1348D01*
G03X331252Y232310I-400J0D01*
G02X330495Y232471I-109J1348D01*
G02X330188Y232700I647J1187D01*
G01X327991Y234888D01*
G02X327647Y235468I954J958D01*
G03X327226Y235754I-384J-112D01*
G02X328398Y237478I-126J1346D01*
G03X328819Y237192I384J112D01*
G02X329899Y236804I126J-1346D01*
G01X330893Y235813D01*
X332067Y234644D01*
X332069Y234642D01*
G02X332494Y233657I-927J-984D01*
G37*
G36*
G01X306155Y223928D02*
G03X305545I-305J-259D01*
G02Y225872I-1145J972D01*
G03X306155I305J259D01*
G02X308327Y225996I1145J-972D01*
G03X308873I273J292D01*
G02Y223804I1027J-1096D01*
G03X308327I-273J-292D01*
G02X306155Y223928I-1027J1096D01*
G37*
G36*
G01X289440Y226672D02*
G03X289723Y226657I149J133D01*
G02X289563Y223553I1478J-1632D01*
G03X289280Y223568I-149J-133D01*
G02X289440Y226672I-1478J1632D01*
G37*
G36*
G01X272482Y223616D02*
G03X273085Y223597I310J253D01*
G02X272992Y220710I1615J-1497D01*
G03X272389Y220729I-310J-253D01*
G02X272482Y223616I-1615J1497D01*
G37*
G36*
G01X333002Y212442D02*
G03X333170Y212212I197J-32D01*
G02X331638Y211083I-196J-1338D01*
G03X331468Y211312I-198J31D01*
G02X330297Y212634I190J1348D01*
G01X330255Y214834D01*
G02X330265Y215030I1361J29D01*
G03X329944Y215472I-397J49D01*
G02X328861Y216614I256J1328D01*
G03X328475Y216959I-396J-55D01*
G02X327484Y217425I35J1361D01*
G01X325998Y219129D01*
G02X325664Y219966I1026J895D01*
G03X325249Y220349I-400J-17D01*
G02X326550Y221765I-49J1351D01*
G03X326967Y221384I400J19D01*
G02X328050Y220919I57J-1360D01*
G01X328829Y220026D01*
X328830D01*
X329535Y219216D01*
G02X329860Y218499I-1025J-897D01*
G03X330243Y218151I397J52D01*
G02X331542Y216639I-43J-1351D01*
G03X331866Y216199I397J-47D01*
G02X332966Y215036I-250J-1339D01*
G01X332974Y214978D01*
X332976Y214921D01*
G02X332978Y214886I-1358J-95D01*
G01Y214860D01*
X333019Y212687D01*
G02Y212667I-1361J-10D01*
G02X333002Y212442I-1361J-10D01*
G37*
G36*
G01X354710Y209927D02*
G03X354753Y209417I328J-229D01*
G02X352679Y209233I-961J-951D01*
G03X352632Y209743I-329J227D01*
G02X352239Y210578I962J963D01*
G01X352030Y212769D01*
G02Y213036I1355J133D01*
G03X351705Y213470I-398J41D01*
G02X353296Y214671I245J1330D01*
G03X353624Y214239I398J-38D01*
G02X354735Y213074I-239J-1341D01*
G01X354736Y213065D01*
X354738Y213055D01*
G02X354740Y213027I-1356J-111D01*
G01X354750Y212922D01*
X354949Y210837D01*
G02X354956Y210717I-1354J-139D01*
G01Y210623D01*
X354945Y210540D01*
G02X354710Y209927I-1351J166D01*
G37*
G36*
G01X340215Y208912D02*
G03X340322Y208647I184J-80D01*
G02X338557Y207932I-522J-1247D01*
G03X338449Y208196I-184J79D01*
G02X337606Y209430I518J1259D01*
G01X337565Y211648D01*
X337564D01*
G02X337570Y211802I1362J24D01*
G03X337286Y212224I-398J39D01*
G02X336509Y214213I384J1296D01*
G03X336433Y214717I-343J206D01*
G02X335980Y215710I908J1014D01*
G01X335946Y217939D01*
X335945D01*
G02X335964Y218183I1362J17D01*
G03X335796Y218413I-197J32D01*
G02X337335Y219537I204J1337D01*
G03X337504Y219308I198J-31D01*
G02X338657Y218137I-197J-1347D01*
G01X338666Y218073D01*
X338668Y218009D01*
Y217961D01*
X338702Y215752D01*
G02Y215738I-1361J-7D01*
G02X338505Y215025I-1361J-8D01*
G03X338578Y214521I342J-208D01*
G02X339017Y213401I-908J-1002D01*
G03X339304Y212982I398J-35D01*
G02X340276Y211850I-378J-1308D01*
G01X340284Y211791D01*
X340286Y211732D01*
G02X340288Y211699I-1358J-99D01*
G01Y211674D01*
X340328Y209480D01*
G02Y209462I-1361J-9D01*
G02X340215Y208912I-1361J-7D01*
G37*
G36*
G01X310908Y206438D02*
G03X310338Y206256I-204J-344D01*
G02X309792Y207962I-1238J544D01*
G03X310362Y208144I204J344D01*
G02X310908Y206438I1238J-544D01*
G37*
G36*
G01X327347Y202556D02*
G03X326988Y202196I39J-398D01*
G02X325511Y203671I-1346J129D01*
G03X325870Y204031I-39J398D01*
G02X327347Y202556I1346J-129D01*
G37*
G36*
G01X322031Y197068D02*
G03X321893Y197316I-192J55D01*
G02X323556Y198246I363J1302D01*
G03X323694Y197998I192J-55D01*
G02X322031Y197068I-363J-1302D01*
G37*
G36*
G01X304913Y194380D02*
G03X304387I-263J-302D01*
G02Y196420I-887J1020D01*
G03X304913I263J302D01*
G02X306644Y196456I887J-1020D01*
G03X307192Y196501I250J312D01*
G02X309087Y196620I1008J-901D01*
G03X309613I263J302D01*
G02Y194580I887J-1020D01*
G03X309087I-263J-302D01*
G02X307356Y194544I-887J1020D01*
G03X306808Y194499I-250J-312D01*
G02X304913Y194380I-1008J901D01*
G37*
G36*
G01X365617Y187672D02*
G03X365573Y187077I244J-317D01*
G02X363775Y187209I-973J-939D01*
G03X363819Y187804I-244J317D01*
G02X363884Y189745I973J939D01*
G03X363898Y190028I-134J148D01*
G02X363964Y191922I997J913D01*
G03X363971Y192205I-137J145D01*
G02X365878Y192160I976J936D01*
G03X365871Y191877I137J-145D01*
G02X365803Y189939I-976J-936D01*
G03X365789Y189656I134J-148D01*
G02X365617Y187672I-997J-913D01*
G37*
G36*
G01X331643Y179854D02*
G03X331137I-253J-309D01*
G02Y181946I-857J1046D01*
G03X331643I253J309D01*
G02X333355Y181948I857J-1046D01*
G03X333860I252J310D01*
G02Y179852I855J-1048D01*
G03X333355I-253J-310D01*
G02X331643Y179854I-855J1048D01*
G37*
G36*
G01X373536Y180424D02*
G03X373490Y179899I277J-289D01*
G02X371464Y180076I-1091J-799D01*
G03X371510Y180601I-277J289D01*
G02X373536Y180424I1091J799D01*
G37*
G36*
G01X365623Y176211D02*
G03X365622Y175686I301J-263D01*
G02X363584Y175692I-1022J-886D01*
G03X363585Y176217I-301J263D01*
G02X365623Y176211I1022J886D01*
G37*
G36*
G01X318552Y214507D02*
Y213763D01*
G03X319077Y213384I400J1D01*
G02X320772Y212557I423J-1284D01*
G03X321252Y212306I377J136D01*
G02X322952Y210966I348J-1306D01*
G01Y209584D01*
G03X323522Y209222I400J0D01*
G02X322891Y207396I578J-1222D01*
G03X322320Y207556I-358J-179D01*
G02X320681Y207708I-720J1144D01*
G03X320019Y207503I-272J-293D01*
G02X319880Y208460I-1319J297D01*
G03X320254Y208576I175J97D01*
G02X320248Y208734I1346J130D01*
G01Y210383D01*
G03X319769Y210775I-400J0D01*
G02X318236Y211620I-269J1325D01*
G03X317711Y211848I-374J-142D01*
G02X315848Y213134I-511J1252D01*
G01Y215266D01*
G02X317673Y216567I1352J34D01*
G03X318175Y216772I140J375D01*
G02X319054Y214893I1225J-572D01*
G03X318552Y214507I-102J-387D01*
G37*
G36*
G01X337043Y197154D02*
G02X337010Y195384I1005J-904D01*
G03X336405Y195396I-308J-256D01*
G02X334860Y197539I-1005J904D01*
G03X334937Y198228I-160J367D01*
G02X336279Y198078I801J1089D01*
G03X336202Y197389I160J-367D01*
G02X336438Y197166I-804J-1087D01*
G03X337043Y197154I308J256D01*
G37*
G36*
G01X370321Y196942D02*
G02X370082Y195419I978J-934D01*
G03X369433Y195521I-360J-174D01*
G02X369672Y197044I-978J934D01*
G03X370321Y196942I360J174D01*
G37*
G36*
G01X330763Y194655D02*
G02X329181I-791J-1096D01*
G03Y195304I-234J325D01*
G02X330763I791J1096D01*
G03Y194655I234J-324D01*
G37*
G36*
G01X327671Y192356D02*
G02X325330Y191017I-1121J-756D01*
G03X324702Y191143I-361J-172D01*
G02X325020Y192733I-902J1007D01*
G03X325648Y192607I361J172D01*
G02X325661Y192619I923J-987D01*
G03X325729Y193144I-263J301D01*
G02X325796Y194747I1121J756D01*
G03X325792Y195254I-311J251D01*
G02X327885Y195272I1039J865D01*
G03X327889Y194765I311J-251D01*
G02X327739Y192881I-1039J-865D01*
G03X327671Y192356I263J-301D01*
G37*
G36*
G01X357780Y191932D02*
G02X355743Y191843I-980J-932D01*
G03X355720Y192368I-313J249D01*
G02X355678Y194185I980J932D01*
G03X355655Y194733I-302J262D01*
G02X355596Y194795I949J962D01*
G03X354917Y194645I-297J-268D01*
G02X354324Y193887I-1292J400D01*
G03Y193203I206J-342D01*
G02X352926I-699J-1158D01*
G03Y193887I-206J342D01*
G02X354629Y195950I699J1157D01*
G03X355308Y196100I297J268D01*
G02X357622Y194815I1292J-400D01*
G03X357645Y194267I302J-262D01*
G02X357757Y192457I-945J-967D01*
G03X357780Y191932I313J-249D01*
G37*
G36*
G01X374805Y191436D02*
G02X373134Y191389I-806J-1086D01*
G03X373117Y192017I-256J307D01*
G02X374929Y194005I805J1086D01*
G03X375586Y194096I298J267D01*
G02X376210Y194716I1213J-597D01*
G03X376233Y195424I-175J360D01*
G02X377490Y195384I667J1176D01*
G03X377467Y194676I175J-360D01*
G02X375793Y192598I-667J-1176D01*
G03X375136Y192507I-298J-267D01*
G02X374788Y192064I-1214J596D01*
G03X374805Y191436I256J-307D01*
G37*
G36*
G01X327614Y187134D02*
G02X325386I-1114J766D01*
G03X324767Y187184I-330J-227D01*
G02X324903Y188883I-978J933D01*
G03X325522Y188833I330J227D01*
G02X327557Y188743I978J-933D01*
G03X328199Y188766I312J250D01*
G02X328256Y187157I1114J-766D01*
G03X327614Y187134I-312J-250D01*
G37*
G36*
G01X350399Y188428D02*
G02X348601Y187952I-648J-1187D01*
G03X348452Y188513I-340J210D01*
G02X348146Y190658I648J1187D01*
G03Y190942I-141J142D01*
G02X348570Y193144I954J958D01*
G03X348684Y193806I-157J368D01*
G02X350130Y193556I916J994D01*
G03X350016Y192894I157J-368D01*
G02X350054Y190942I-916J-994D01*
G03Y190658I141J-142D01*
G02X350250Y188989I-954J-958D01*
G03X350399Y188428I340J-210D01*
G37*
G36*
G01X369831Y187264D02*
G02X368334Y187363I-823J-1073D01*
G03X368378Y188027I-199J347D01*
G02X368354Y190154I822J1073D01*
G03X368332Y190794I-251J312D01*
G02X369952Y190849I773J1109D01*
G03X369974Y190209I251J-312D01*
G02X369875Y187928I-774J-1109D01*
G03X369831Y187264I199J-347D01*
G37*
G36*
G01X336204Y184884D02*
G02X333855Y184781I-1204J616D01*
G03X333193Y184804I-339J-213D01*
G02X331506Y186814I-1093J796D01*
G03X331596Y187085I-88J180D01*
G02X332920Y189047I1204J615D01*
G03X333356Y189431I36J398D01*
G02X333634Y190205I1351J-48D01*
G03X333471Y190817I-318J243D01*
G02X335069Y191241I525J1246D01*
G03X335232Y190629I318J-243D01*
G02X335938Y189943I-525J-1246D01*
G03X336644Y189901I364J165D01*
G02X337101Y190358I1157J-700D01*
G03Y191042I-206J342D01*
G02X338499I699J1158D01*
G03Y190358I206J-342D01*
G02X336569Y188640I-699J-1157D01*
G03X335863Y188682I-364J-165D01*
G02X334587Y188036I-1156J701D01*
G03X334151Y187652I-36J-398D01*
G02X333394Y186486I-1351J48D01*
G03X333304Y186215I88J-180D01*
G02X333380Y186036I-1203J-617D01*
G03X333753Y186023I189J65D01*
G02X336111Y186270I1247J-523D01*
G03X336796Y186316I329J228D01*
G02X336889Y184930I1204J-615D01*
G03X336204Y184884I-329J-228D01*
G37*
G36*
G01X343232Y184220D02*
G02X341178Y184260I-1044J-859D01*
G03X341189Y184780I-298J266D01*
G02X341424Y186722I1044J859D01*
G03X341544Y187218I-239J320D01*
G02X341581Y188472I1216J592D01*
G03X341486Y188978I-348J196D01*
G02X341387Y190981I856J1046D01*
G03Y191265I-141J142D01*
G02X343294Y191268I952J960D01*
G03Y190984I141J-142D01*
G02X343521Y189362I-952J-960D01*
G03X343616Y188856I348J-196D01*
G02X343970Y188413I-856J-1047D01*
G03X344626Y188324I358J178D01*
G02X344938Y188581I1006J-903D01*
G03X344908Y189284I-205J343D01*
G02X344786Y191648I592J1216D01*
G03X344787Y192327I-211J340D01*
G02X346217Y192326I716J1147D01*
G03X346216Y191647I211J-340D01*
G02X346193Y189339I-716J-1147D01*
G03X346223Y188636I205J-343D01*
G02X346325Y186260I-592J-1216D01*
G03X346295Y185593I205J-343D01*
G02X344806Y185660I-795J-1093D01*
G03X344836Y186327I-205J343D01*
G02X344421Y186817I795J1094D01*
G03X343765Y186906I-358J-178D01*
G02X343569Y186727I-1005J904D01*
G03X343449Y186231I239J-320D01*
G02X343243Y184740I-1216J-592D01*
G03X343232Y184220I298J-266D01*
G37*
G36*
G01X354092Y181239D02*
G02X352535Y181228I-771J-1111D01*
G03X352531Y181882I-232J326D01*
G02X354088Y181893I771J1111D01*
G03X354092Y181239I232J-326D01*
G37*
G36*
G01X324120Y181265D02*
G02X322588Y181061I-620J-1202D01*
G03X322501Y181711I-270J295D01*
G02X324033Y181915I620J1202D01*
G03X324120Y181265I270J-295D01*
G37*
G36*
G01X361988Y179599D02*
G02X360483Y179646I-788J-1099D01*
G03X360504Y180310I-212J339D01*
G02X360658Y182603I788J1099D01*
G03X360660Y183309I-187J354D01*
G02X360710Y185716I640J1191D01*
G03X360733Y186424I-175J360D01*
G02X360718Y188767I667J1176D01*
G03X360685Y189475I-202J345D01*
G02X360457Y191790I572J1225D01*
G03Y192434I-237J322D01*
G02X362057I800J1090D01*
G03Y191790I237J-322D01*
G02X361939Y189533I-800J-1090D01*
G03X361972Y188825I202J-345D01*
G02X361990Y186384I-572J-1225D01*
G03X361967Y185676I175J-360D01*
G02X361934Y183306I-667J-1176D01*
G03X361932Y182600I187J-354D01*
G02X362009Y180263I-640J-1191D01*
G03X361988Y179599I212J-339D01*
G37*
G36*
G01X335069Y176657D02*
G02X332636Y176612I-1227J567D01*
G03X331947Y176653I-356J-181D01*
G02X332027Y178014I-1126J749D01*
G03X332716Y177973I356J181D01*
G02X334986Y177944I1126J-749D01*
G03X335688Y177990I339J213D01*
G02X338086Y178098I1227J-567D01*
G03X338762Y178071I347J200D01*
G02X338704Y176628I1113J-767D01*
G03X338028Y176655I-347J-200D01*
G02X335771Y176703I-1113J768D01*
G03X335069Y176657I-339J-213D01*
G37*
G36*
G01X377542Y176789D02*
G02X376095Y176775I-712J-1149D01*
G03X376088Y177451I-217J336D01*
G02X376033Y179713I712J1149D01*
G03X376020Y180381I-227J330D01*
G02X377509Y180411I722J1143D01*
G03X377522Y179743I227J-330D01*
G02X377535Y177465I-722J-1143D01*
G03X377542Y176789I217J-336D01*
G37*
G36*
G01X333308Y172999D02*
G02X331325Y172964I-1008J901D01*
G03X330806Y173014I-289J-277D01*
G02X329068Y173166I-779J1105D01*
G03X328514Y173178I-283J-282D01*
G02X326990Y175380I-915J995D01*
G03X327014Y176081I-181J357D01*
G02X328318Y176035I694J1160D01*
G03X328294Y175334I181J-357D01*
G02X328559Y175127I-693J-1161D01*
G03X329113Y175115I283J282D01*
G02X331002Y175055I914J-996D01*
G03X331521Y175005I289J277D01*
G02X333144Y174956I779J-1105D01*
G03X333692Y175001I250J312D01*
G02X335587Y175121I1008J-901D01*
G03X336112I263J302D01*
G02X337888I888J-1019D01*
G03X338413I263J302D01*
G02X338412Y173081I887J-1020D01*
G03X337887I-262J-302D01*
G02X336113I-887J1021D01*
G03X335588I-263J-302D01*
G02X333856Y173044I-888J1019D01*
G03X333308Y172999I-250J-312D01*
G37*
G36*
G01X343096Y170294D02*
G02X343023Y168742I1069J-828D01*
G03X342369Y168772I-338J-214D01*
G02X342442Y170324I-1069J828D01*
G03X343096Y170294I338J214D01*
G37*
G36*
G01X327587Y168755D02*
G02X327560Y170095I-1188J646D01*
G03X328254Y170109I343J205D01*
G02X330550Y170238I1188J-646D01*
G03X331215Y170251I328J229D01*
G02X333512Y170219I1139J-729D01*
G03X334207Y170237I342J206D01*
G02X334241Y168903I1193J-637D01*
G03X333546Y168885I-342J-206D01*
G02X331245Y168747I-1193J637D01*
G03X330580Y168734I-328J-229D01*
G02X328281Y168769I-1139J729D01*
G03X327587Y168755I-343J-205D01*
G37*
G36*
G01X368687Y169664D02*
G02X367240Y169618I-687J-1164D01*
G03X367219Y170294I-224J331D01*
G02X369005Y172245I687J1164D01*
G03X369689Y172300I325J233D01*
G02X371670Y170589I1211J-600D01*
G03X371716Y169904I228J-329D01*
G02X370330Y169811I-615J-1204D01*
G03X370284Y170496I-228J329D01*
G02X369801Y170913I617J1203D01*
G03X369117Y170858I-325J-233D01*
G02X368666Y170340I-1212J600D01*
G03X368687Y169664I224J-331D01*
G37*
G36*
G01X384277Y169528D02*
G02X382348Y167767I-729J-1138D01*
G03X381652Y167792I-355J-184D01*
G02X381700Y169123I-1152J708D01*
G03X382396Y169098I355J184D01*
G02X382931Y169593I1152J-708D01*
G03X382964Y170286I-183J356D01*
G02X384310Y170221I730J1138D01*
G03X384277Y169528I183J-356D01*
G37*
G36*
G01X378618Y164480D02*
G02Y166000I-1118J760D01*
G03X379280I331J225D01*
G02Y164480I1118J-760D01*
G03X378618I-331J-225D01*
G37*
G36*
G01X385599Y162818D02*
G02X385580Y161526I1178J-663D01*
G03X384878Y161536I-354J-187D01*
G02X383057Y163388I-1178J663D01*
G03X383076Y164082I-190J352D01*
G02X384931Y165946I705J1153D01*
G03X385620Y165961I340J210D01*
G02X385650Y164589I1180J-661D01*
G03X384961Y164574I-340J-210D01*
G02X384424Y164046I-1179J662D01*
G03X384405Y163352I190J-352D01*
G02X384897Y162828I-704J-1154D01*
G03X385599Y162818I354J187D01*
G37*
G36*
G01X352839Y163060D02*
G02X350852Y162715I-839J-1060D01*
G03X350761Y163240I-339J212D01*
G02X350941Y165481I839J1060D01*
G03X350964Y166166I-194J349D01*
G02X350643Y168143I736J1134D01*
G03X350620Y168668I-313J249D01*
G02X350841Y170719I980J932D01*
G03X350978Y171221I-224J331D01*
G02X352959Y170681I1222J579D01*
G03X352822Y170179I224J-331D01*
G02X352657Y168757I-1222J-579D01*
G03X352680Y168232I313J-249D01*
G02X352359Y166119I-980J-932D01*
G03X352336Y165434I194J-349D01*
G02X352748Y163585I-736J-1134D01*
G03X352839Y163060I339J-212D01*
G37*
G36*
G01X368703Y160323D02*
G02X367313Y160392I-752J-1123D01*
G03X367347Y161077I-189J353D01*
G02X367470Y163396I753J1123D01*
G03Y164104I-187J354D01*
G02X368730I630J1196D01*
G03Y163396I187J-354D01*
G02X369254Y162905I-629J-1197D01*
G03X369952Y162932I341J208D01*
G02X370003Y161615I1205J-613D01*
G03X369305Y161588I-341J-208D01*
G02X368737Y161008I-1205J612D01*
G03X368703Y160323I189J-353D01*
G37*
G36*
G01X372357Y158282D02*
G02X372251Y159760I-1181J658D01*
G03X372919Y159808I318J242D01*
G02X373025Y158330I1181J-658D01*
G03X372357Y158282I-318J-242D01*
G37*
G36*
G01X394342Y155054D02*
G02Y156526I-1134J736D01*
G03X395014I336J217D01*
G02Y155054I1134J-736D01*
G03X394342I-336J-217D01*
G37*
G36*
G01X381145Y147695D02*
G02X379747Y147753I-747J-1127D01*
G03X379775Y148437I-193J350D01*
G02X379320Y148946I748J1126D01*
G03X378624Y148974I-356J-183D01*
G02X378678Y150306I-1148J714D01*
G03X379374Y150278I356J183D01*
G02X381692Y150242I1148J-714D01*
G03X382389Y150251I346J201D01*
G02X384240Y148426I1186J-648D01*
G03X384234Y147733I197J-348D01*
G02X382883Y147745I-686J-1165D01*
G03X382889Y148438I-197J348D01*
G02X382405Y148925I686J1165D01*
G03X381708Y148916I-346J-201D01*
G02X381173Y148379I-1187J647D01*
G03X381145Y147695I193J-350D01*
G37*
G36*
G01X382265Y144048D02*
G02X382212Y142651I1130J-742D01*
G03X381528Y142676I-350J-194D01*
G02X381581Y144073I-1130J742D01*
G03X382265Y144048I350J194D01*
G37*
G36*
G01X388062Y142444D02*
G02X388037Y144147I-1062J836D01*
G03X388659Y144156I307J256D01*
G02X388684Y142453I1062J-836D01*
G03X388062Y142444I-307J-256D01*
G37*
G36*
G01X272190Y187351D02*
G03X271684Y187182I-159J-367D01*
G02X270642Y190297I-1912J1092D01*
G03X271148Y190466I159J367D01*
G02X274679Y190866I1912J-1092D01*
G03X275271Y190870I294J271D01*
G02X275291Y187908I1639J-1470D01*
G03X274699Y187904I-294J-271D01*
G02X272190Y187351I-1639J1470D01*
G37*
G36*
G01X308197Y157718D02*
G03X307671Y157673I-237J-322D01*
G02X307499Y159698I-975J937D01*
G03X308025Y159743I237J322D01*
G02X309899Y159815I974J-937D01*
G03X310411Y159799I266J299D01*
G02X310343Y157723I831J-1066D01*
G03X309831Y157739I-266J-299D01*
G02X308197Y157718I-831J1067D01*
G37*
G36*
G01X310513Y152815D02*
G03X310230Y152800I-134J-148D01*
G02X308340Y152672I-1010J898D01*
G03X307824Y152676I-260J-304D01*
G02X307841Y154743I-863J1041D01*
G03X308357Y154739I260J304D01*
G02X310124Y154704I863J-1041D01*
G03X310407Y154719I134J148D01*
G02X310513Y152815I1010J-899D01*
G37*
G36*
G01X327026Y141033D02*
G03X326743Y141027I-139J-144D01*
G02X324840Y140970I-980J931D01*
G03X324335Y141003I-273J-292D01*
G02X324473Y143092I-785J1101D01*
G03X324978Y143059I273J292D01*
G02X326700Y142933I785J-1101D01*
G03X326983Y142939I139J144D01*
G02X328921Y142962I980J-931D01*
G03X329205I142J141D01*
G02Y141054I958J-954D01*
G03X328921I-142J-141D01*
G02X327026Y141033I-958J954D01*
G37*
G36*
G01X338023Y142619D02*
G03X338174Y142859I-44J195D01*
G02X339788Y141844I1317J304D01*
G03X339637Y141604I44J-195D01*
G02X337185Y140565I-1317J-304D01*
G03X336699Y140718I-336J-218D01*
G02X337325Y142705I-509J1252D01*
G03X337811Y142552I336J218D01*
G02X338023Y142619I512J-1251D01*
G37*
G36*
G01X352011Y137699D02*
G03X352171Y137174I358J-178D01*
G02X350289Y136601I-671J-1174D01*
G03X350129Y137126I-358J178D01*
G02X352011Y137699I671J1174D01*
G37*
G36*
G01X325103Y129283D02*
G03X325450Y128701I356J-182D01*
G02X324358Y126509I-32J-1352D01*
G03X323808Y126583I-313J-248D01*
G02X322437Y128898I-801J1089D01*
G03X322641Y129407I-168J363D01*
G02X325103Y129283I1259J493D01*
G37*
G36*
G01X284655Y189570D02*
G02X283514Y191333I-2195J-170D01*
G03X284105Y191715I192J351D01*
G02X285246Y189952I2195J170D01*
G03X284655Y189570I-192J-351D01*
G37*
G36*
G01X362346Y147737D02*
G02X360900Y147639I-646J-1188D01*
G03X360854Y148312I-237J322D01*
G02X362300Y148410I646J1188D01*
G03X362346Y147737I237J-322D01*
G37*
G36*
G01X356162Y147676D02*
G02X354742Y147682I-715J-1148D01*
G03X354745Y148362I-209J341D01*
G02X356165Y148356I715J1148D01*
G03X356162Y147676I209J-341D01*
G37*
G36*
G01X345807Y141354D02*
G02X344582Y143050I-1307J346D01*
G03X344993Y143346I25J399D01*
G02X345527Y144109I1307J-346D01*
G03X345459Y144804I-228J328D01*
G02X347049Y146895I540J1239D01*
G03X347676Y146902I311J252D01*
G02X348063Y147240I1067J-831D01*
G03Y147932I-202J346D01*
G02X347849Y148085I676J1171D01*
G03X347326Y148090I-264J-300D01*
G02X347344Y150135I-876J1030D01*
G03X347867Y150130I264J300D01*
G02X349423Y147932I876J-1029D01*
G03Y147240I202J-346D01*
G02X349556Y144992I-680J-1168D01*
G03X349540Y144365I240J-320D01*
G02X347893Y142223I-865J-1039D01*
G03X347350Y142149I-232J-326D01*
G02X346218Y141650I-1051J851D01*
G03X345807Y141354I-25J-399D01*
G37*
G36*
G01X357324Y137667D02*
G02X357284Y136410I1176J-667D01*
G03X356576Y136433I-360J-175D01*
G02X356616Y137690I-1176J667D01*
G03X357324Y137667I360J175D01*
G37*
G36*
G01X342792Y135149D02*
G02X341208Y134088I-259J-1327D01*
G03X341050Y134324I-196J40D01*
G02X340156Y134945I259J1327D01*
G03X339475Y134948I-341J-208D01*
G02X337266Y134830I-1146J717D01*
G03X336575Y134719I-315J-247D01*
G02X334720Y136398I-1272J459D01*
G03X334768Y137092I-173J361D01*
G02X334335Y137559I747J1127D01*
G03X333642Y137567I-349J-196D01*
G02X331304Y137584I-1164J688D01*
G03X330606Y137578I-347J-198D01*
G02X330595Y138899I-1185J651D01*
G03X331293Y138905I347J198D01*
G02X333657Y138916I1185J-650D01*
G03X334350Y138908I349J196D01*
G02X336665Y138929I1164J-688D01*
G03X337340Y138919I341J210D01*
G02X339565Y138969I1130J-742D01*
G03X340221Y138980I324J235D01*
G02X342247Y137219I1121J-757D01*
G03X342239Y136632I268J-297D01*
G02X342634Y135385I-930J-981D01*
G03X342792Y135149I196J-40D01*
G37*
G36*
G01X329042Y129788D02*
G02X328994Y131161I-1188J646D01*
G03X329682Y131186I337J216D01*
G02X329730Y129813I1188J-646D01*
G03X329042Y129788I-337J-216D01*
G37*
G36*
G01X338453Y128449D02*
G02X338271Y126480I827J-1069D01*
G03X337727Y126531I-299J-266D01*
G02X335752Y126885I-828J1069D01*
G03X335085Y126903I-339J-211D01*
G02X335125Y128393I-1108J775D01*
G03X335792Y128375I339J211D01*
G02X337909Y128500I1108J-775D01*
G03X338453Y128449I299J266D01*
G37*
G36*
G01X594263Y143411D02*
G03X593718Y143405I-269J-296D01*
G02X593681Y146630I-1518J1595D01*
G03X594226Y146636I269J296D01*
G02X594263Y143411I1518J-1595D01*
G37*
G36*
G01X760603Y105665D02*
G03X760885Y105641I153J129D01*
G02X760617Y102542I1419J-1684D01*
G03X760335Y102566I-153J-129D01*
G02X760603Y105665I-1419J1684D01*
G37*
G36*
G01X728525Y96869D02*
G03X729048Y96776I314J248D01*
G02X728475Y93531I1152J-1877D01*
G03X727952Y93624I-314J-248D01*
G02X728525Y96869I-1152J1877D01*
G37*
G36*
G01X745907Y21998D02*
G03X745884Y21427I268J-297D01*
G02X743993Y21502I-984J-927D01*
G03X744016Y22073I-268J297D01*
G02X745907Y21998I984J927D01*
G37*
G36*
G01X773500Y28775D02*
Y16000D01*
X772348Y14848D01*
X772470Y14707D01*
G02X768101Y12000I-1970J-1700D01*
G01X754000D01*
X751064Y14936D01*
X750927Y14846D01*
G02X749835Y17578I-827J1254D01*
G01X750000Y17608D01*
Y57500D01*
X754500Y62000D01*
X768500D01*
X773500Y57000D01*
Y33839D01*
G03X773992Y33450I400J0D01*
G02X775981Y32937I508J-2143D01*
G03X776519I269J296D01*
G02Y29677I1481J-1630D01*
G03X775981I-269J-296D01*
G02X773992Y29164I-1481J1630D01*
G03X773500Y28775I-92J-389D01*
G37*
G36*
G01X707000Y94686D02*
G02X705036Y95699I-1855J-1186D01*
G03X705354Y96314I-19J400D01*
G02X707318Y95301I1855J1186D01*
G03X707000Y94686I19J-400D01*
G37*
G36*
G01X789391Y13017D02*
G02X788201Y11112I1109J-2017D01*
G03X787609Y11483I-400J20D01*
G02X788799Y13388I-1109J2017D01*
G03X789391Y13017I400J-20D01*
G37*
G36*
G01X653595Y263686D02*
G03X653420Y263136I176J-359D01*
G02X651638Y263703I-1187J-647D01*
G03X651813Y264253I-176J359D01*
G02X653595Y263686I1187J647D01*
G37*
G36*
G01X649388Y263767D02*
G02X647931Y263380I-440J-1278D01*
G03X647760Y264022I-301J264D01*
G02X649217Y264409I440J1278D01*
G03X649388Y263767I301J-264D01*
G37*
G36*
G01X592136Y253300D02*
G02X590515Y253276I-794J-1094D01*
G03X590506Y253916I-244J317D01*
G02X592127Y253940I794J1094D01*
G03X592136Y253300I244J-317D01*
G37*
G36*
G01X643817Y253080D02*
G02X641956Y253240I-1014J-894D01*
G03X642005Y253816I-251J311D01*
G02X644281Y255197I1015J894D01*
G03X644943Y255065I373J144D01*
G02X647270Y254066I977J-935D01*
G03X647700Y253648I400J-19D01*
G02X646450Y252364I100J-1348D01*
G03X646020Y252782I-400J19D01*
G02X644659Y253643I-100J1348D01*
G03X643997Y253775I-373J-144D01*
G02X643866Y253656I-973J939D01*
G03X643817Y253080I251J-311D01*
G37*
G36*
G01X610557Y253307D02*
G02X608980Y253061I-620J-1201D01*
G03X608880Y253699I-283J282D01*
G02X608234Y254426I620J1201D01*
G03X607594Y254586I-375J-140D01*
G02X606006Y254440I-894J1014D01*
G03X605406Y254164I-206J-343D01*
G02X604768Y255554I-1332J230D01*
G03X605368Y255830I206J343D01*
G02X607966Y256074I1332J-230D01*
G03X608606Y255914I375J140D01*
G02X610457Y253945I893J-1015D01*
G03X610557Y253307I283J-282D01*
G37*
G36*
G01X648326Y29343D02*
G02X645715Y29188I-1326J264D01*
G03X645053Y29348I-380J-124D01*
G02X643259Y31366I-952J960D01*
G03X643168Y32047I-248J313D01*
G02X644541Y32231I532J1243D01*
G03X644632Y31550I248J-313D01*
G02X645385Y30726I-532J-1243D01*
G03X646047Y30566I380J124D01*
G02X647642Y30797I953J-959D01*
G03X648224Y31071I190J352D01*
G02X648908Y29617I1326J-264D01*
G03X648326Y29343I-190J-352D01*
G37*
G54D30*
X120200Y45610D03*
X136600Y44800D03*
X238800Y45300D03*
X261900Y44900D03*
X269800Y44800D03*
X321900Y44000D03*
X305300Y203125D03*
X307231Y164059D03*
G54D28*
X14400Y98000D03*
X353100Y56151D03*
X37500Y264000D03*
X129500Y252500D03*
X129000Y268000D03*
X166500Y241000D03*
X216261Y74846D03*
X345089Y73089D03*
X721200Y65100D03*
X732000Y63500D03*
G54D29*
X41200Y90300D03*
X60800Y87500D03*
X62900Y79900D03*
X138000Y49800D03*
X143688Y48350D03*
X219899Y56800D03*
X223475Y53300D03*
X240200Y59275D03*
X244400Y50600D03*
X278868Y56000D03*
X300900Y46900D03*
X16844Y203100D03*
X40500Y124300D03*
X53500Y120400D03*
X58000Y141750D03*
X58800Y177000D03*
X69235Y99735D03*
X75300Y259900D03*
X90500Y101000D03*
X86100Y97700D03*
X86500Y113500D03*
X80500D03*
X82100Y259600D03*
X88900Y246700D03*
X100600Y221100D03*
X110166Y239500D03*
X104900Y248800D03*
X97600Y246500D03*
X109500Y258300D03*
X112700Y231400D03*
X146000Y231000D03*
X146500Y236500D03*
X155300Y254000D03*
X144200Y270700D03*
X165700Y254000D03*
X195000Y234000D03*
X206000D03*
X137138Y76512D03*
X264500Y73100D03*
X264125Y79350D03*
X275200Y78700D03*
X318882Y71643D03*
X323882D03*
X337000Y74202D03*
X328882Y71643D03*
X186300Y172400D03*
X263600Y239850D03*
X278450Y216800D03*
X265259Y216659D03*
X275400Y237900D03*
X293300Y212400D03*
X287700Y211900D03*
X295300Y238100D03*
X287600D03*
X278300Y173300D03*
X287071Y173154D03*
X282950Y181350D03*
X528400Y145041D03*
X608300Y144890D03*
X653600Y122400D03*
X718900Y94000D03*
X724200Y108400D03*
X736900Y98500D03*
X749500Y101500D03*
X765500Y112000D03*
X725500Y195500D03*
X731000Y210200D03*
X740300Y164700D03*
X733000Y176200D03*
G54D32*
X326408Y182292D03*
X319942Y180524D03*
X324436Y175705D03*
X323165Y171937D03*
X320029Y184300D03*
X316844Y196010D03*
X319801Y194890D03*
X315585Y207787D03*
X337863Y180545D03*
X342029Y196427D03*
X329028Y199931D03*
X336500Y204600D03*
X348432Y164844D03*
X347500Y169500D03*
X350000Y177700D03*
X355300Y174600D03*
X345562Y178700D03*
X347200Y174300D03*
X353342Y186124D03*
X356900Y186100D03*
X345837Y199887D03*
X350409Y199755D03*
X354700Y199900D03*
X358342Y165324D03*
X364600Y165300D03*
Y171600D03*
X369021Y180128D03*
X361500Y168500D03*
Y175000D03*
X359222Y197700D03*
X369450Y212040D03*
X371100Y199500D03*
X365250Y208600D03*
X374200Y149494D03*
X386853Y149640D03*
X374200Y143294D03*
X380400Y152700D03*
X383500Y159000D03*
X380500Y162025D03*
X386777Y159005D03*
X387000Y155850D03*
X377500Y156000D03*
X374300Y155800D03*
X380477Y171605D03*
X393204Y146436D03*
X389848Y146568D03*
X399298Y165240D03*
X392998D03*
X396225Y171686D03*
X393085D03*
X399385D03*
X399300Y168400D03*
X393077Y168455D03*
X410100Y157700D03*
X413314Y154908D03*
X311000Y141731D03*
X325746Y133702D03*
X322691Y136023D03*
X320321Y130528D03*
X317698Y152311D03*
X319252Y140949D03*
X319401Y149354D03*
X326322Y138434D03*
X323000Y153900D03*
X329693Y134428D03*
X336920Y146130D03*
X346495Y130000D03*
X347641Y133479D03*
X342880Y146180D03*
X355342Y143424D03*
X364600Y137063D03*
X361726Y140268D03*
X594600Y6707D03*
X690102Y12502D03*
X692200Y15357D03*
X709000Y12407D03*
X702000Y12607D03*
X698277Y22855D03*
X705031Y14515D03*
X708900Y30407D03*
X704430Y33313D03*
X701800Y30807D03*
X723586Y14080D03*
X712182Y14124D03*
X718375Y22907D03*
X715090D03*
X720100Y14707D03*
X727000Y30407D03*
X712400Y30807D03*
X721747Y32954D03*
X723500Y29907D03*
X742200Y12407D03*
X728010Y12857D03*
X739000Y14407D03*
X731169Y14584D03*
X736091Y23607D03*
X732806D03*
X742100Y33007D03*
X740200Y29907D03*
X730500D03*
X747441Y33007D03*
X598398Y260199D03*
X590837Y259889D03*
X594600Y260000D03*
X598300Y265400D03*
X594500Y265200D03*
X590700Y264833D03*
X611706Y259387D03*
X619382Y260089D03*
X615532Y259700D03*
X619100Y265300D03*
X611536Y264385D03*
X615537Y264789D03*
X630432Y260100D03*
X626682Y260300D03*
X622933Y260189D03*
X634207Y260300D03*
X634280Y265332D03*
X626651Y265489D03*
X622899Y265189D03*
X630455Y265400D03*
X638900Y254809D03*
X635043Y252106D03*
X638032Y260342D03*
X638090Y265340D03*
X644550Y267170D03*
X615907Y24856D03*
X615852Y19807D03*
X616707Y15616D03*
X618900Y33290D03*
X631000Y20107D03*
X630955Y25207D03*
X634757Y20207D03*
X634555Y25307D03*
X623532Y20007D03*
X627231Y19907D03*
X627255Y25107D03*
X619607Y19807D03*
X619730Y24864D03*
X623555Y25107D03*
X642246Y25807D03*
X642451Y20707D03*
X638290Y25674D03*
X638400Y20607D03*
X655602Y25223D03*
X655700Y20225D03*
X657900Y30690D03*
X732200Y252200D03*
X741560Y255000D03*
X735168Y262489D03*
X732740Y270200D03*
X738453Y262489D03*
X744437Y252189D03*
G54D34*
X502500Y6200D03*
X756400Y110500D03*
G54D35*
X794032Y27032D03*
X804032Y37032D03*
Y47032D03*
X794032Y37032D03*
Y47032D03*
X804032Y57032D03*
X794032D03*
Y67032D03*
G54D33*
X804032Y27032D03*
Y67032D03*
G54D31*
X350197Y231103D03*
G54D26*
X11500Y68500D03*
X12000Y279000D03*
G54D27*
X45669Y77185D03*
Y172460D03*
%LPD*%
G75*
G36*
G01X771500Y16000D02*
X771052Y15552D01*
X770949Y15570D01*
G03X767979Y13651I-449J-2563D01*
G01X767940Y13500D01*
X754500D01*
X752000Y16000D01*
Y46407D01*
G02X752415Y46807I400J0D01*
G03Y51207I85J2200D01*
G02X752000Y51607I-15J400D01*
G01Y57500D01*
X755000Y60500D01*
X767500D01*
X771500Y56500D01*
Y16000D01*
G37*
%LPC*%
G75*
G54D28*
X759000Y37507D03*
G54D36*
X761417Y22798D03*
%LPD*%
G75*
G54D10*
X15400Y118000D03*
X10900D03*
X13000Y137000D03*
X15500Y122800D03*
X15000Y127500D03*
X11000Y122800D03*
X10500Y127500D03*
X13000Y141500D03*
X13100Y150600D03*
X13000Y146000D03*
X14500Y198000D03*
X4500Y228900D03*
X4600Y223100D03*
X4500Y234800D03*
X4400Y245100D03*
Y256700D03*
X5000Y275000D03*
X12600Y266900D03*
X15300Y285800D03*
X4900Y285700D03*
X25200Y286000D03*
X45500Y118000D03*
X63500Y43500D03*
Y57500D03*
Y48000D03*
Y52500D03*
X50500Y160000D03*
X68500Y47500D03*
X73500Y48000D03*
X68000Y52500D03*
X70900Y193800D03*
X95500Y93500D03*
X94000Y137500D03*
Y133000D03*
X82000Y177500D03*
X99500Y91500D03*
Y96000D03*
X104000Y106600D03*
Y92000D03*
Y96500D03*
Y115500D03*
Y111000D03*
X105775Y137349D03*
X103175Y134050D03*
X98500Y137500D03*
X109000Y134050D03*
X98500Y133000D03*
X119400Y106700D03*
X123800Y102500D03*
X123900Y106700D03*
X119400Y102300D03*
Y115900D03*
Y111200D03*
X123900Y115900D03*
Y111200D03*
X114500Y134050D03*
X119000Y159100D03*
X114700Y158800D03*
X122250Y228750D03*
Y233000D03*
Y237300D03*
Y241500D03*
X134100Y96600D03*
X136500Y272500D03*
X189000Y87700D03*
X192500Y161900D03*
X192600Y166700D03*
X201200Y164200D03*
X203100Y252900D03*
X212300Y157300D03*
X212600Y161500D03*
X211900Y253000D03*
X207500D03*
X226900Y133300D03*
X234525Y239250D03*
X229700Y234700D03*
X225300Y239200D03*
X234525Y243450D03*
X229725D03*
X225300Y243400D03*
X234525Y234800D03*
X225300D03*
X229675Y239000D03*
X233500Y258958D03*
X228000Y259000D03*
X249350Y199400D03*
X247500Y239250D03*
X243300Y235050D03*
X247500Y243450D03*
X243300D03*
X238900D03*
X243300Y239250D03*
X247500Y235050D03*
X238925Y235000D03*
Y239200D03*
X248000Y259000D03*
X238500D03*
X243000D03*
X252350Y202350D03*
X251700Y239250D03*
Y243450D03*
X252500Y259000D03*
X353500Y71900D03*
X357000Y69500D03*
X349300Y83000D03*
X345100D03*
X354200Y76400D03*
X371400Y42500D03*
X371500Y47000D03*
X359800Y72700D03*
X362700Y69600D03*
X380000Y38100D03*
X375600Y42500D03*
X380300D03*
X375700Y47000D03*
X380295Y46779D03*
X474000Y9000D03*
X467200Y4400D03*
X481500Y8900D03*
X489600Y8800D03*
X497100D03*
X598814Y240095D03*
X615100Y238900D03*
X623900Y239600D03*
X646000Y46007D03*
X640000D03*
X654500Y46107D03*
X653000Y93000D03*
X650726Y125724D03*
X659811Y260757D03*
X657500Y258400D03*
X661308Y263698D03*
X655500Y270500D03*
X657787Y264179D03*
X656000Y261400D03*
X655523Y266616D03*
X658667Y267622D03*
X678400Y114500D03*
X700089Y91411D03*
X701600Y104900D03*
X701400Y98400D03*
X710200Y201700D03*
X725632Y49600D03*
X721950Y51950D03*
X722000Y74500D03*
X717000D03*
X715000Y80300D03*
X714500Y85500D03*
X739500Y75500D03*
X753500Y24007D03*
Y20007D03*
Y28507D03*
X755500Y16000D03*
X767500Y24007D03*
X760500Y29000D03*
X761000Y16007D03*
X767500Y28507D03*
Y19507D03*
X764200Y44200D03*
X767500Y33207D03*
X764500Y54000D03*
X764300Y49200D03*
X769500Y50000D03*
X761000Y58500D03*
X764500Y84800D03*
X760400Y88700D03*
X768100Y89000D03*
X761300Y95700D03*
X763600Y168000D03*
X764000Y188000D03*
Y197500D03*
Y192810D03*
Y202310D03*
X769500Y234500D03*
X769400Y252700D03*
X785500Y8000D03*
X781500Y51000D03*
X777000Y93100D03*
X774300Y102500D03*
X778500D03*
Y107000D03*
X774300D03*
X785830Y188700D03*
X785400Y202800D03*
X789000Y204979D03*
X789200Y214200D03*
Y209800D03*
X784500Y222500D03*
X789000Y223500D03*
X789200Y218700D03*
X786000Y228000D03*
Y232400D03*
X786200Y236900D03*
X786300Y241500D03*
X785000Y245800D03*
Y250200D03*
Y254900D03*
X792000Y83000D03*
X796500D03*
X792000Y87700D03*
X796500D03*
X789910Y187679D03*
X794110D03*
X798310Y187779D03*
X793500Y204979D03*
Y223500D03*
X793200Y228400D03*
Y232600D03*
Y237200D03*
Y242400D03*
X793300Y247200D03*
X795300Y260800D03*
X795400Y251700D03*
X795300Y256500D03*
Y265000D03*
X810500Y196500D03*
Y192300D03*
X809200Y209500D03*
Y213700D03*
Y218400D03*
X809100Y228600D03*
Y224400D03*
X808700Y238300D03*
Y234100D03*
Y242900D03*
X809500Y251500D03*
Y257000D03*
X808700Y247100D03*
X810100Y275000D03*
X812035Y271067D03*
X810100Y267339D03*
X812000Y263500D03*
X809700Y285900D03*
X820500Y6500D03*
X821900Y273100D03*
X821600Y285500D03*
G54D20*
G01X303500Y123582D02*
X303600D01*
X303850Y123832D01*
X305232D01*
X305734Y124334D01*
X307834D01*
X308284Y123884D01*
Y123484D01*
X307500Y122700D01*
G01X303500Y124882D02*
X303600D01*
X303850Y124632D01*
X304900D01*
X305402Y125134D01*
X308166D01*
X309084Y124216D01*
Y123412D01*
X309700Y122796D01*
G01X306994Y117725D02*
X310269Y121000D01*
X315400D01*
X317000Y122600D01*
Y124368D01*
X313268Y128100D01*
X306968D01*
X304818Y130250D01*
X303350D01*
X303100Y130000D01*
X303000D01*
G01X309194Y117700D02*
X309192Y117702D01*
Y118791D01*
X310601Y120200D01*
X315732D01*
X317800Y122268D01*
Y124700D01*
X313600Y128900D01*
X307300D01*
X305150Y131050D01*
X303350D01*
X303100Y131300D01*
X303000D01*
G01X328300Y112400D02*
Y112500D01*
X328050Y112750D01*
Y114712D01*
X332138Y118800D01*
X332774D01*
X333534Y118040D01*
G01X327000Y112400D02*
Y112500D01*
X327250Y112750D01*
Y115044D01*
X331806Y119600D01*
X332701D01*
X333601Y120500D01*
G01X379600Y131350D02*
X379850Y131600D01*
X403200D01*
X404120Y132520D01*
X408600D01*
X410440Y130680D01*
Y128572D01*
X410212Y128344D01*
Y122156D01*
X410700Y121668D01*
Y121017D01*
X412167Y119550D01*
X414033D01*
X415178Y120695D01*
X415800D01*
X416904Y119591D01*
G01X379600Y132650D02*
X379650D01*
X379900Y132400D01*
X402868D01*
X403788Y133320D01*
X408932D01*
X411240Y131012D01*
Y128240D01*
X411012Y128012D01*
Y122488D01*
X411500Y122000D01*
Y121349D01*
X412499Y120350D01*
X413701D01*
X414846Y121495D01*
X415746D01*
X416851Y122600D01*
G01X329415Y119923D02*
X328638Y120700D01*
X327816D01*
X325265Y118149D01*
Y117597D01*
X324416Y116749D01*
X323865D01*
X323016Y115900D01*
X321816D01*
X321426Y115510D01*
X320226D01*
X319836Y115900D01*
X316332D01*
X315081Y114649D01*
Y114097D01*
X314232Y113249D01*
X313681D01*
X312832Y112400D01*
X303868D01*
X302145Y114123D01*
X301791D01*
X301721Y114193D01*
G01X329308Y122386D02*
X328422Y121500D01*
X327484D01*
X322684Y116700D01*
X316000D01*
X312500Y113200D01*
X304200D01*
X302711Y114689D01*
Y115043D01*
X302641Y115113D01*
G01X405496Y97104D02*
X402000Y100600D01*
X388600D01*
X382596Y106604D01*
Y108600D01*
G01X381600Y119900D02*
X383500Y121800D01*
Y122900D01*
X384582Y123982D01*
X386124D01*
X390603Y119503D01*
Y115804D01*
X395985Y110422D01*
X401499D01*
X403110Y108811D01*
G01X421463Y100891D02*
X421393Y100961D01*
Y101175D01*
X420568Y102000D01*
X416823D01*
X412852Y105968D01*
X398175D01*
X389003Y115140D01*
Y117424D01*
X386899Y119528D01*
X385721D01*
G01X407400Y102600D02*
X406700Y103300D01*
X396000D01*
X393300Y106000D01*
X390200D01*
X388424Y107776D01*
Y109176D01*
X385200Y112400D01*
Y113137D01*
G01X409200Y90700D02*
Y95700D01*
X403100Y101800D01*
X394874D01*
X392574Y104100D01*
X389100D01*
X384378Y108822D01*
Y110522D01*
X381900Y113000D01*
G01X385600Y116500D02*
X387900Y114200D01*
Y111500D01*
X389388Y110012D01*
X391788D01*
G01X422241Y101669D02*
X422171Y101739D01*
X421961D01*
X420900Y102800D01*
X417155D01*
X413184Y106768D01*
X398507D01*
X389803Y115472D01*
Y117756D01*
X385523Y122036D01*
Y122532D01*
G01X381500Y123200D02*
G02X379900Y126400I2400J3200D01*
G01Y126700D01*
G02X380350Y127949I1958J0D01*
G01X380700Y128299D01*
X382703Y129304D01*
G02X385600Y130006I2897J-5627D01*
G02X387239Y129157I0J-2007D01*
G01X388593Y126679D01*
X389300Y126100D01*
X390900D01*
X393300Y125500D01*
X394300D01*
X395900Y123900D01*
Y123376D01*
X398190Y121086D01*
X401902D01*
G01X385479Y125569D02*
X385669D01*
X391403Y119835D01*
Y117254D01*
X392100Y116557D01*
X393952D01*
X396596Y113913D01*
X397201D01*
X397246Y113868D01*
X402350D01*
X403199Y113019D01*
Y111601D01*
X403800Y111000D01*
G01X402154Y117954D02*
X402096Y118012D01*
X400752D01*
X400738Y117998D01*
X399402D01*
X397951Y119449D01*
X394120D01*
X393897Y119672D01*
X392698D01*
X387985Y124385D01*
G02X387664Y125493I1752J1108D01*
G03X387503Y126001I-2123J-393D01*
G03X386080Y127019I-1423J-486D01*
G01X382192D01*
X381600Y126427D01*
G01X400417Y189875D02*
Y188817D01*
X398757Y187157D01*
Y186006D01*
X398750Y185999D01*
Y184450D01*
X396900Y182600D01*
X396200D01*
X392250Y178650D01*
X386050D01*
X384740Y179960D01*
Y180080D01*
G01X410100Y191756D02*
Y189800D01*
X406792Y186492D01*
Y183823D01*
X406708Y183739D01*
Y177400D01*
X406108Y176800D01*
X404400D01*
X403700Y177500D01*
X384440D01*
X381720Y180220D01*
G01X400545Y197814D02*
X399000Y196269D01*
Y195349D01*
X395779Y192128D01*
X395228D01*
X394092Y190992D01*
Y186986D01*
X393197Y186091D01*
X392127D01*
X390618Y184582D01*
G03X390100Y183331I1251J-1251D01*
G01Y182700D01*
G03X390631Y181418I1813J0D01*
G01X390774Y181275D01*
X390795Y181253D01*
G02X391149Y180400I-853J-854D01*
G01Y180149D01*
X390600Y179600D01*
X387800D01*
X385700Y181700D01*
X380210D01*
X379750Y181240D01*
Y178160D01*
X380540Y177370D01*
G01X391563Y197509D02*
Y197295D01*
X390468Y196200D01*
X388868D01*
X386700Y194032D01*
Y188032D01*
X386368Y187700D01*
X385918D01*
X384708Y188910D01*
G01X404000Y216600D02*
X398800Y211400D01*
X390600D01*
X390000Y212000D01*
Y213700D01*
X389400Y214300D01*
X383100D01*
X382500Y213700D01*
Y204900D01*
X384021Y203379D01*
Y199200D01*
X381460Y196639D01*
Y195610D01*
G01X397500Y197500D02*
X396600Y196600D01*
X395983D01*
G03X395500Y196400I0J-683D01*
G01X394683Y195583D01*
G03X394400Y194900I683J-683D01*
G01Y192900D01*
X393613Y192113D01*
X391713D01*
X391000Y191400D01*
Y186900D01*
X388730Y184630D01*
X384000D01*
G03X382515Y184015I0J-2100D01*
G01X381800Y183300D01*
G01X389047Y200000D02*
Y197652D01*
X384895Y193500D01*
X384041D01*
X382111Y191570D01*
X381300D01*
X381280Y191550D01*
G01X381140Y187960D02*
X381010Y188090D01*
X380520D01*
X379200Y189410D01*
Y192600D01*
X380170Y193570D01*
X382696D01*
X383626Y194500D01*
X384580D01*
X387590Y197510D01*
Y201990D01*
G01X403171Y211871D02*
X400678D01*
X399007Y210200D01*
X392100D01*
X391900Y210000D01*
X389100D01*
X388700Y210400D01*
Y212200D01*
X387400Y213500D01*
X386400D01*
X384574Y211674D01*
Y210826D01*
X386700Y208700D01*
Y204900D01*
X385700Y203900D01*
Y197780D01*
X384390Y196470D01*
G01X392341Y196731D02*
X392131D01*
X390800Y195400D01*
X389200D01*
X387500Y193700D01*
Y187700D01*
X386700Y186900D01*
X385363D01*
X384600Y186137D01*
Y186100D01*
G01X386100Y234094D02*
X387500Y232694D01*
Y220000D01*
X385900Y218400D01*
G01X382719Y242559D02*
Y234581D01*
X385947Y231353D01*
Y226500D01*
G01X397300Y89168D02*
Y89165D01*
X396535Y88400D01*
Y82397D01*
X410032Y68900D01*
X410800D01*
G01X412400Y71200D02*
X410800D01*
X407900Y74100D01*
X406900D01*
X398850Y82150D01*
Y96950D01*
X400400Y98500D01*
G01X390600Y77351D02*
Y89200D01*
X390700Y89300D01*
G01X393900Y77305D02*
X392500Y78705D01*
Y97400D01*
X394100Y99000D01*
G01X400400Y92200D02*
Y82200D01*
X407500Y75100D01*
X410200D01*
X411800Y73500D01*
G01X394100Y80358D02*
Y91400D01*
G01X389000Y75698D02*
Y94750D01*
X390750Y96500D01*
G01X415200Y75800D02*
X412600D01*
X411000Y77400D01*
X406800D01*
X402000Y82200D01*
Y88500D01*
X403700Y90200D01*
G01X397100Y96600D02*
X395735Y95235D01*
Y82065D01*
X410000Y67800D01*
G01X392950Y223194D02*
X391950Y222194D01*
Y220800D01*
G01X391850Y223850D02*
X390100Y222100D01*
Y215700D01*
X392100Y213700D01*
G01X390900Y235800D02*
Y225800D01*
X389100Y224000D01*
G01X389150Y230300D02*
Y234297D01*
G01X403726Y83826D02*
Y82474D01*
X407600Y78600D01*
X412300D01*
G01X416485Y113250D02*
X415735Y114000D01*
X411500D01*
X410800Y114700D01*
Y115700D01*
X409900Y116600D01*
X408500D01*
X407660Y117440D01*
Y122260D01*
X408200Y122800D01*
Y129308D01*
X408956Y130064D01*
G01X422200Y111300D02*
X421996Y111504D01*
X419504D01*
X418146Y112862D01*
Y114646D01*
X418372Y114872D01*
Y117214D01*
X418350Y117236D01*
Y118986D01*
X418354Y118990D01*
Y123446D01*
X416700Y125100D01*
X415800D01*
X413272Y127628D01*
Y129872D01*
X414800Y131400D01*
X415000D01*
G01X415100Y127900D02*
X415200Y127800D01*
Y127732D01*
X419154Y123778D01*
Y118658D01*
X419150Y118654D01*
Y117568D01*
X419172Y117546D01*
Y115928D01*
X420187Y114913D01*
X420197D01*
X421046Y114064D01*
Y114054D01*
X424500Y110600D01*
X432300D01*
X436500Y106400D01*
G01X440500Y158000D02*
X422888D01*
X420014Y158771D01*
X417178Y161178D01*
X416335Y162021D01*
Y165900D01*
X415975Y166453D01*
X415879Y166572D01*
X413265Y170423D01*
G01X436800Y161700D02*
X431646D01*
X431143Y162203D01*
X423311D01*
X420914Y164600D01*
X420100D01*
G02X418059Y165446I1J2887D01*
G01X417857Y165647D01*
X417117Y166387D01*
X416400Y168678D01*
Y170300D01*
G01X433835Y199065D02*
G03X433032Y198733I-1J-1135D01*
G01X432771Y198471D01*
X432000Y197700D01*
Y196400D01*
X427650Y192050D01*
Y189750D01*
X426800Y188900D01*
X423900D01*
X423000Y188000D01*
X420600D01*
X417355Y184755D01*
X415255D01*
X413200Y182700D01*
Y179875D01*
X414670Y178405D01*
X414685D01*
X414960Y178130D01*
G01X429500Y198900D02*
X429499D01*
X428483Y197884D01*
Y197883D01*
X425400Y194800D01*
X420100D01*
X418700Y193400D01*
Y191700D01*
X417600Y190600D01*
Y188400D01*
X416855Y187655D01*
X414955D01*
X413900Y186600D01*
Y184900D01*
X411553Y182553D01*
Y181222D01*
G01X427496Y200303D02*
X425565Y198372D01*
X420652D01*
X420624Y198400D01*
X416400D01*
X414300Y196300D01*
Y189900D01*
X413350Y188950D01*
X411250D01*
X409892Y187592D01*
Y179458D01*
X411260Y178090D01*
G01X436600Y197800D02*
Y196600D01*
X437320Y195880D01*
Y194406D01*
X437137Y194223D01*
X437092D01*
X434000Y191131D01*
Y189600D01*
X432400Y188000D01*
X424900D01*
X423700Y186800D01*
Y185700D01*
X422850Y184850D01*
X421570D01*
X420300Y183580D01*
Y182200D01*
X419224Y181124D01*
X415286D01*
X414950Y181460D01*
G01X420942Y131324D02*
X421400D01*
X422000Y130724D01*
Y130132D01*
X420000Y128132D01*
Y125230D01*
X422130Y123100D01*
X426535D01*
X427772Y121863D01*
X430554D01*
X432688Y119729D01*
Y113018D01*
X435537Y110169D01*
X439831D01*
X440000Y110000D01*
G01X423900Y131500D02*
X422800Y130400D01*
Y129800D01*
X420800Y127800D01*
Y125562D01*
X422462Y123900D01*
X426867D01*
X428104Y122663D01*
X430886D01*
X433488Y120061D01*
Y113350D01*
X435869Y110969D01*
X439869D01*
X440000Y111100D01*
G01X438758Y107800D02*
X436774D01*
X429600Y114974D01*
Y117500D01*
X428800Y118300D01*
X427300D01*
X426000Y117000D01*
X424400D01*
X422700Y118700D01*
Y121398D01*
X419200Y124898D01*
Y127500D01*
X418500Y128200D01*
G01X423500D02*
X425000Y129700D01*
X428100D01*
X430000Y127800D01*
Y125514D01*
X430903Y124611D01*
X431604D01*
X437757Y118458D01*
X439942D01*
G01X427000Y128050D02*
X426500Y127550D01*
Y125940D01*
X428740Y123700D01*
X431100D01*
X435696Y119104D01*
Y116417D01*
X437013Y115100D01*
G01X419453Y173187D02*
X420790Y171850D01*
Y169910D01*
X421701Y168999D01*
X423101D01*
X424480Y167620D01*
Y166839D01*
X425399Y165920D01*
X428500D01*
X429680Y167100D01*
Y167261D01*
X430529Y168110D01*
X431989D01*
X432096Y168004D01*
X434000Y166100D01*
X439000D01*
G01X436600Y165000D02*
X436333Y165267D01*
X433767D01*
X431563Y163063D01*
X423745D01*
X421408Y165400D01*
X420649D01*
G02X419695Y165795I0J1349D01*
G01X418439Y167051D01*
Y167118D01*
G01X439800Y185900D02*
X437357Y183457D01*
X433659D01*
X431602Y181400D01*
X430410D01*
X430360Y181350D01*
G01X450600Y190800D02*
X439071Y179271D01*
X433115D01*
X432944Y179100D01*
X427760D01*
X426970Y178310D01*
G01X464909Y166865D02*
X463844Y165800D01*
X443200D01*
X439000Y170000D01*
X431868D01*
X431601Y169733D01*
X428962D01*
X428431Y170264D01*
G01X446200Y177900D02*
X442630Y174330D01*
X440070D01*
X439180Y175220D01*
X436133D01*
X435632Y174719D01*
X431779D01*
X431128Y175370D01*
X427060D01*
X425427Y173737D01*
Y173113D01*
G01X452681Y187300D02*
X449773D01*
X440336Y177863D01*
X435691D01*
X435083Y178471D01*
X433447D01*
X432596Y177620D01*
X430340D01*
G01X422337Y170575D02*
X422330Y170582D01*
Y172069D01*
X426431Y176170D01*
X431460D01*
X432111Y175519D01*
X435300D01*
X435881Y176100D01*
X441200D01*
X448700Y183600D01*
X450300D01*
G01X448500Y192000D02*
X447400Y190900D01*
Y190300D01*
X439100Y182000D01*
X436363D01*
X435706Y182657D01*
X434504D01*
X431747Y179900D01*
X429400D01*
X427926Y181374D01*
X423642D01*
G01X444800Y173000D02*
X444500Y172700D01*
X434719D01*
X433500Y173919D01*
X431447D01*
X430796Y174570D01*
X427392D01*
X426950Y174128D01*
Y171862D01*
X425480Y170392D01*
Y170320D01*
X425400Y170240D01*
G01X437357Y187515D02*
X437287Y187445D01*
X437077D01*
X436479Y186847D01*
X434679D01*
X430972Y183140D01*
X423040D01*
X421996Y182096D01*
Y180604D01*
X422584Y180016D01*
Y179532D01*
X423842Y178274D01*
G01X436579Y188293D02*
X436509Y188223D01*
Y188009D01*
X436147Y187647D01*
X434347D01*
X430640Y183940D01*
X422708D01*
X421196Y182428D01*
Y180272D01*
X421784Y179684D01*
Y178600D01*
X421301Y178117D01*
X420922D01*
G01X465565Y165965D02*
X465141D01*
X464176Y165000D01*
X442868D01*
X438668Y169200D01*
X432200D01*
X431933Y168933D01*
X429474D01*
X428250Y167709D01*
X428238D01*
G01X442500Y171019D02*
X432111D01*
X430010Y173120D01*
X428500D01*
G54D11*
G01X10636Y-27865D02*
G02I-12000J0D01*
G01X14636D02*
X-17364D01*
G01X5486D02*
G02I-6850J0D01*
G01X-1364Y-43865D02*
Y-11865D01*
G01X14636Y-43865D02*
Y-123865D01*
G01D02*
X1309236D01*
G01X14636Y-79365D02*
X1309236D01*
G01X14636Y-43865D02*
X1309236D01*
G01X70900Y193800D02*
Y188257D01*
X76657Y182500D01*
X106755D01*
X118077Y171180D01*
G01X157229Y119218D02*
X157161Y119150D01*
X157148D01*
X154500Y116502D01*
Y112253D01*
X151747Y109500D01*
X145178D01*
X138778Y115900D01*
X123900D01*
G01X118077Y171180D02*
X127257Y162000D01*
X147013D01*
X148709Y163696D01*
X152823D01*
X154699Y161820D01*
X158500D01*
G01X198000Y167000D02*
Y169996D01*
X192471Y175525D01*
X192417D01*
X188200Y179742D01*
Y180408D01*
X183316Y185292D01*
X164686D01*
X159798Y180404D01*
Y168000D01*
X158500Y166702D01*
Y161820D01*
G01X228000Y139700D02*
Y143943D01*
X229052Y144995D01*
Y150205D01*
X211836Y167421D01*
X205101D01*
X193797Y178725D01*
X193743D01*
X191400Y181068D01*
X191200D01*
G01X247596Y174667D02*
Y167704D01*
X262900Y152400D01*
X268265D01*
X270765Y149900D01*
X272300D01*
G01X257687Y169870D02*
X261457Y166100D01*
X271300D01*
X274100Y163300D01*
G01X270341Y211835D02*
X268206Y209700D01*
X261200D01*
G01X322650Y161150D02*
Y164580D01*
X321779Y165451D01*
Y166321D01*
X310000Y178100D01*
X302038D01*
X299000Y181138D01*
Y190939D01*
X278104Y211835D01*
X270341D01*
G01X304400Y88400D02*
X307400Y85400D01*
X327735D01*
X328085Y85050D01*
X335874D01*
X336624Y85800D01*
X352791D01*
X366700Y71891D01*
Y68700D01*
G01X521736Y-43865D02*
Y-123865D01*
G01X659236Y-43865D02*
Y-123865D01*
G01X699000Y162255D02*
X701245Y164500D01*
Y183800D01*
G01X714900Y131900D02*
X725600Y142600D01*
X757400D01*
X764000Y136000D01*
X781000D01*
X782000Y137000D01*
G01X774236Y-43865D02*
Y-123865D01*
G01X941736Y-43865D02*
Y-123865D01*
G01X1111736Y-43865D02*
Y-123865D01*
G01X1309236Y-43865D02*
Y-123865D01*
G01X1341236Y-27865D02*
X1309236D01*
G01X1337236D02*
G02I-12000J0D01*
G01X1332086D02*
G02I-6850J0D01*
G01X1325236Y-43865D02*
Y-11865D01*
X17500Y190200D03*
X17301Y212401D03*
X17300Y218307D03*
X10000Y229500D03*
X16400Y224212D03*
X16118Y230118D03*
X10194Y243106D03*
X9500Y234200D03*
X16899Y241929D03*
X16300Y236023D03*
X10190Y258510D03*
X10194Y254917D03*
X10190Y246699D03*
X16899Y247834D03*
Y253740D03*
Y259645D03*
X16900Y269000D03*
X7600Y268100D03*
X16899Y265551D03*
X32800Y120400D03*
X29200Y120300D03*
X30000Y196200D03*
X33500Y196100D03*
X21900Y205400D03*
X31500Y207500D03*
X40500Y127700D03*
X38500Y148000D03*
X48500D03*
X41000Y152300D03*
Y143300D03*
X46000D03*
Y152300D03*
X43500Y148000D03*
Y138500D03*
X48500D03*
X38500D03*
X45800Y158100D03*
X37600Y198800D03*
X34800D03*
X40400Y212700D03*
Y207800D03*
X34800Y203700D03*
X37600Y212700D03*
Y207800D03*
Y203700D03*
X34500Y216000D03*
X40400Y217100D03*
X40700Y224000D03*
X40200Y238300D03*
Y231300D03*
Y245300D03*
X40500Y260000D03*
X40600Y252500D03*
X46800Y274500D03*
X52500Y96500D03*
Y106500D03*
X57500Y96500D03*
X60000Y101500D03*
X50000D03*
X55000D03*
X57500Y106500D03*
X60000Y111300D03*
X50000D03*
X55000D03*
X57600Y136900D03*
X52643Y130800D03*
X54700Y192200D03*
X52700Y184800D03*
X62800Y184300D03*
X57600Y214200D03*
X57400Y210700D03*
X57600Y226600D03*
X57287Y219806D03*
X56724Y243300D03*
X56800Y249613D03*
X58102Y246471D03*
X57800Y253900D03*
X66500Y128000D03*
X79500Y230000D03*
X78700Y259800D03*
X67600Y255800D03*
X66300Y259300D03*
X74000Y271400D03*
X67000Y263200D03*
X84500Y230000D03*
X89500D03*
X84500Y225000D03*
Y235000D03*
X91400Y270300D03*
X99600Y225700D03*
X99328Y235370D03*
X109000Y231400D03*
X118500Y125500D03*
X125000Y178000D03*
X111900Y209000D03*
X136469Y89902D03*
X130315Y90533D03*
X133558Y91779D03*
X130563Y125200D03*
X127500Y129180D03*
X133786Y134700D03*
X130300Y135000D03*
X131500Y149000D03*
X136156Y138025D03*
X131762Y141796D03*
X128000Y203300D03*
X147400Y60400D03*
X157229Y119218D03*
X147808Y145208D03*
X146400Y138595D03*
X150500Y183000D03*
X157000Y169194D03*
X146980Y200580D03*
X153500Y210000D03*
X146396Y207675D03*
X142997Y207891D03*
X150000Y210100D03*
X157500Y149025D03*
X158500Y161820D03*
X161900Y161700D03*
X167581Y164084D03*
X170910Y173840D03*
X167140D03*
X165900Y181500D03*
X163700Y178900D03*
X162000Y226000D03*
X167000D03*
Y221500D03*
X162000D03*
Y230500D03*
X167000D03*
X162000Y235000D03*
X174900Y77700D03*
X187500Y106500D03*
X181732Y97500D03*
X177200Y148700D03*
X180931Y172985D03*
X177159Y172900D03*
X176800Y241600D03*
X202200Y89500D03*
X201650Y111200D03*
X201899Y134200D03*
X197140Y152010D03*
X194623Y149723D03*
X191200Y181068D03*
X198198Y206374D03*
X206605Y121741D03*
X209900Y120900D03*
X205380Y134200D03*
X215100Y194200D03*
X207861Y188540D03*
X205920Y221550D03*
X216000Y219500D03*
X226500Y94450D03*
X230875Y106300D03*
X227894Y104600D03*
X227800Y101200D03*
X228000Y108304D03*
Y139700D03*
X232560Y204250D03*
X240297Y63400D03*
X236700Y88500D03*
X241200Y94900D03*
X244800Y100700D03*
X234875Y139290D03*
Y143060D03*
X247596Y174667D03*
X240100Y191000D03*
X257687Y169870D03*
X261300Y188300D03*
X253300Y189834D03*
X262700Y191500D03*
X261200Y209700D03*
X263600Y252700D03*
X280100Y89100D03*
X272300Y149900D03*
X278000Y141900D03*
X273900Y156198D03*
X274100Y163300D03*
X270341Y211835D03*
X267275Y253400D03*
X265500Y249300D03*
X269800Y250700D03*
X267000Y271300D03*
X281005Y99105D03*
X281500Y142100D03*
X295900Y154200D03*
X299800Y85950D03*
X304400Y88400D03*
X301600Y93300D03*
X303376Y95200D03*
X297000Y160200D03*
X304300Y262900D03*
X366700Y68700D03*
X369500Y237200D03*
Y240600D03*
X373000Y242300D03*
X369500Y234600D03*
Y244000D03*
X393000Y275000D03*
X430000Y27358D03*
Y30758D03*
X449734Y18681D03*
X480400Y154050D03*
X467100Y154200D03*
X477000Y154050D03*
X470100Y154200D03*
X473500Y154050D03*
X466500Y272800D03*
X483800Y154050D03*
X487200Y154100D03*
X524700Y145041D03*
X552100Y136000D03*
X557100D03*
X572100D03*
X567100D03*
X562000Y127800D03*
X562100Y136000D03*
X562000Y144900D03*
X588800Y145000D03*
X599200D03*
X617700Y125500D03*
X618500Y159000D03*
X625500D03*
X629000D03*
X622000D03*
X633319Y155008D03*
X639500Y136490D03*
X636719Y154972D03*
X643500Y155000D03*
X640110Y155272D03*
X701245Y183800D03*
X714900Y131900D03*
X718200Y147000D03*
Y150400D03*
X718825Y155453D03*
X717000Y187500D03*
X715500Y205837D03*
X738000Y65700D03*
X738500Y90000D03*
X731340Y82515D03*
X739500Y114900D03*
X732000Y122700D03*
X736900Y162300D03*
X729500D03*
X733400D03*
X737000Y188315D03*
X739900Y212800D03*
X734000Y205000D03*
X739800Y216300D03*
X756000Y106000D03*
X747000Y162000D03*
X750500D03*
X746000Y182300D03*
X743000Y211000D03*
X744100Y221900D03*
X743800Y215900D03*
X768500Y114000D03*
X805500Y128000D03*
G54D21*
G01X70851Y-113865D02*
Y-96365D01*
G01X80021D02*
Y-113865D01*
G01Y-105115D02*
X70851D01*
G01X92936Y-113865D02*
X91626Y-113573D01*
X90316Y-112407D01*
X89442Y-110365D01*
X89006Y-108032D01*
X89442Y-105698D01*
X90316Y-103657D01*
X91626Y-102490D01*
X92936Y-102199D01*
X94246Y-102490D01*
X95556Y-103657D01*
X96429Y-105698D01*
X96648Y-108032D01*
X96429Y-110365D01*
X95556Y-112407D01*
X94246Y-113573D01*
X92936Y-113865D01*
G01X106724D02*
Y-102199D01*
G01Y-105115D02*
X107598Y-103657D01*
X108908Y-102490D01*
X110654Y-102199D01*
X112182Y-102490D01*
X113493Y-103657D01*
X114148Y-105698D01*
Y-113865D01*
G01X124661Y-105990D02*
X131648D01*
X130993Y-103948D01*
X129901Y-102782D01*
X128373Y-102199D01*
X126844Y-102490D01*
X125534Y-103365D01*
X124661Y-105407D01*
X124224Y-107157D01*
Y-108907D01*
X124661Y-110657D01*
X125753Y-112407D01*
X127063Y-113573D01*
X128591Y-113865D01*
X130119Y-113282D01*
X131648Y-111532D01*
G01X140851Y-119115D02*
X142161Y-119698D01*
X143908Y-119115D01*
X144999Y-117949D01*
X145873Y-116490D01*
X147182Y-111824D01*
X150021Y-102199D01*
G01X143034D02*
X147182Y-111824D01*
G01X182182Y-104532D02*
X183056Y-103657D01*
X183711Y-102199D01*
X184148Y-100156D01*
X183711Y-98407D01*
X182838Y-97240D01*
X181309Y-96365D01*
X175414D01*
Y-113865D01*
X182619D01*
X184148Y-112699D01*
X185021Y-110948D01*
X185458Y-108907D01*
X185021Y-106865D01*
X183711Y-105115D01*
X182182Y-104532D01*
X175414D01*
G01X201866Y-113865D02*
Y-102199D01*
G01Y-104240D02*
X200993Y-103074D01*
X199682Y-102490D01*
X198154Y-102199D01*
X196626Y-102782D01*
X195316Y-103948D01*
X194442Y-105698D01*
X194006Y-108032D01*
X194442Y-110365D01*
X195316Y-112115D01*
X196626Y-113282D01*
X198154Y-113865D01*
X199682Y-113573D01*
X200993Y-112699D01*
X201866Y-111532D01*
G01X219366Y-96365D02*
Y-113865D01*
G01Y-111241D02*
X218493Y-112699D01*
X217182Y-113573D01*
X215654Y-113865D01*
X213908Y-113282D01*
X212598Y-111824D01*
X211724Y-110074D01*
X211506Y-108032D01*
X211724Y-105990D01*
X212598Y-104240D01*
X213908Y-102782D01*
X215654Y-102199D01*
X217182Y-102490D01*
X218274Y-103074D01*
X219366Y-104240D01*
G01X229879Y-118240D02*
X231408Y-119407D01*
X233154Y-119698D01*
X234682Y-119407D01*
X235993Y-117949D01*
X236866Y-115907D01*
Y-102199D01*
G01Y-104532D02*
X235993Y-103365D01*
X234682Y-102490D01*
X233154Y-102199D01*
X231408Y-102782D01*
X230316Y-103948D01*
X229442Y-105990D01*
X229006Y-108032D01*
X229224Y-109782D01*
X230098Y-111824D01*
X231408Y-113282D01*
X233154Y-113865D01*
X234464Y-113573D01*
X235993Y-112407D01*
X236866Y-111241D01*
G01X247161Y-105990D02*
X254148D01*
X253493Y-103948D01*
X252401Y-102782D01*
X250873Y-102199D01*
X249344Y-102490D01*
X248034Y-103365D01*
X247161Y-105407D01*
X246724Y-107157D01*
Y-108907D01*
X247161Y-110657D01*
X248253Y-112407D01*
X249563Y-113573D01*
X251091Y-113865D01*
X252619Y-113282D01*
X254148Y-111532D01*
G01X264879Y-113865D02*
Y-102199D01*
G01Y-104532D02*
X265971Y-103365D01*
X267063Y-102490D01*
X268591Y-102199D01*
X269682Y-102490D01*
X270993Y-103365D01*
G01X298569Y-113865D02*
Y-96365D01*
X303809D01*
X305556Y-97240D01*
X306866Y-99282D01*
X307303Y-101615D01*
X306866Y-103948D01*
X305774Y-105698D01*
X303809Y-106574D01*
X298569D01*
G01X324366Y-113865D02*
Y-102199D01*
G01Y-104240D02*
X323493Y-103074D01*
X322182Y-102490D01*
X320654Y-102199D01*
X319126Y-102782D01*
X317816Y-103948D01*
X316942Y-105698D01*
X316506Y-108032D01*
X316942Y-110365D01*
X317816Y-112115D01*
X319126Y-113282D01*
X320654Y-113865D01*
X322182Y-113573D01*
X323493Y-112699D01*
X324366Y-111532D01*
G01X334224Y-113865D02*
Y-102199D01*
G01Y-105115D02*
X335098Y-103657D01*
X336408Y-102490D01*
X338154Y-102199D01*
X339682Y-102490D01*
X340993Y-103657D01*
X341648Y-105698D01*
Y-113865D01*
G01X355436Y-96365D02*
Y-113865D01*
G01X352379Y-102199D02*
X358493D01*
G01X369224Y-113865D02*
Y-96365D01*
G01Y-104823D02*
X370316Y-103365D01*
X371408Y-102490D01*
X373154Y-102199D01*
X374464Y-102490D01*
X375993Y-103657D01*
X376648Y-105407D01*
Y-113865D01*
G01X387161Y-105990D02*
X394148D01*
X393493Y-103948D01*
X392401Y-102782D01*
X390873Y-102199D01*
X389344Y-102490D01*
X388034Y-103365D01*
X387161Y-105407D01*
X386724Y-107157D01*
Y-108907D01*
X387161Y-110657D01*
X388253Y-112407D01*
X389563Y-113573D01*
X391091Y-113865D01*
X392619Y-113282D01*
X394148Y-111532D01*
G01X404879Y-113865D02*
Y-102199D01*
G01Y-104532D02*
X405971Y-103365D01*
X407063Y-102490D01*
X408591Y-102199D01*
X409682Y-102490D01*
X410993Y-103365D01*
G01X437259Y-113865D02*
Y-96365D01*
X442936Y-110948D01*
X448613Y-96365D01*
Y-113865D01*
G01X462182Y-104532D02*
X463056Y-103657D01*
X463711Y-102199D01*
X464148Y-100156D01*
X463711Y-98407D01*
X462838Y-97240D01*
X461309Y-96365D01*
X455414D01*
Y-113865D01*
X462619D01*
X464148Y-112699D01*
X465021Y-110948D01*
X465458Y-108907D01*
X465021Y-106865D01*
X463711Y-105115D01*
X462182Y-104532D01*
X455414D01*
G01X227259Y-68865D02*
Y-51365D01*
X232936Y-65948D01*
X238613Y-51365D01*
Y-68865D01*
G01X250436D02*
X249126Y-68573D01*
X247816Y-67407D01*
X246942Y-65365D01*
X246506Y-63032D01*
X246942Y-60698D01*
X247816Y-58657D01*
X249126Y-57490D01*
X250436Y-57199D01*
X251746Y-57490D01*
X253056Y-58657D01*
X253929Y-60698D01*
X254148Y-63032D01*
X253929Y-65365D01*
X253056Y-67407D01*
X251746Y-68573D01*
X250436Y-68865D01*
G01X271866Y-51365D02*
Y-68865D01*
G01Y-66241D02*
X270993Y-67699D01*
X269682Y-68573D01*
X268154Y-68865D01*
X266408Y-68282D01*
X265098Y-66824D01*
X264224Y-65074D01*
X264006Y-63032D01*
X264224Y-60990D01*
X265098Y-59240D01*
X266408Y-57782D01*
X268154Y-57199D01*
X269682Y-57490D01*
X270774Y-58074D01*
X271866Y-59240D01*
G01X282161Y-60990D02*
X289148D01*
X288493Y-58948D01*
X287401Y-57782D01*
X285873Y-57199D01*
X284344Y-57490D01*
X283034Y-58365D01*
X282161Y-60407D01*
X281724Y-62157D01*
Y-63907D01*
X282161Y-65657D01*
X283253Y-67407D01*
X284563Y-68573D01*
X286091Y-68865D01*
X287619Y-68282D01*
X289148Y-66532D01*
G01X302936Y-68865D02*
Y-51365D01*
G01X542319Y-68865D02*
Y-51365D01*
X547559D01*
X549306Y-52240D01*
X550616Y-54282D01*
X551053Y-56615D01*
X550616Y-58948D01*
X549524Y-60698D01*
X547559Y-61574D01*
X542319D01*
G01X568989Y-52824D02*
X567679Y-51948D01*
X566151Y-51365D01*
X564404D01*
X562439Y-52240D01*
X560911Y-53698D01*
X559819Y-55449D01*
X558946Y-58365D01*
X558727Y-60990D01*
X559164Y-63615D01*
X559819Y-65365D01*
X561129Y-67115D01*
X562658Y-68282D01*
X564186Y-68865D01*
X565714D01*
X567243Y-68282D01*
X568553Y-67407D01*
X569645Y-66241D01*
G01X583432Y-59532D02*
X584306Y-58657D01*
X584961Y-57199D01*
X585398Y-55156D01*
X584961Y-53407D01*
X584088Y-52240D01*
X582559Y-51365D01*
X576664D01*
Y-68865D01*
X583869D01*
X585398Y-67699D01*
X586271Y-65948D01*
X586708Y-63907D01*
X586271Y-61865D01*
X584961Y-60115D01*
X583432Y-59532D01*
X576664D01*
G01X592636Y-74698D02*
X605736D01*
G01X611664Y-68865D02*
Y-51365D01*
X621708Y-68865D01*
Y-51365D01*
G01X634186Y-68865D02*
X632439Y-68573D01*
X630911Y-67407D01*
X629601Y-65657D01*
X628727Y-63615D01*
X628291Y-61282D01*
Y-58948D01*
X628727Y-56615D01*
X629601Y-54573D01*
X630911Y-52824D01*
X632439Y-51657D01*
X634186Y-51365D01*
X635932Y-51657D01*
X637461Y-52824D01*
X638771Y-54573D01*
X639645Y-56615D01*
X640081Y-58948D01*
Y-61282D01*
X639645Y-63615D01*
X638771Y-65657D01*
X637461Y-67407D01*
X635932Y-68573D01*
X634186Y-68865D01*
G01X555436Y-113865D02*
Y-96365D01*
X552816Y-99865D01*
G01Y-113865D02*
X558056D01*
G01X568133Y-110365D02*
X569442Y-112407D01*
X571189Y-113573D01*
X573154Y-113865D01*
X574901Y-113573D01*
X576648Y-112115D01*
X577739Y-110365D01*
X577958Y-108615D01*
X577521Y-106574D01*
X575993Y-105115D01*
X574464Y-104532D01*
X572499D01*
G01X574464D02*
X575774Y-103657D01*
X576866Y-102199D01*
X577303Y-100449D01*
X576866Y-98698D01*
X575774Y-97240D01*
X573809Y-96365D01*
X571844Y-96657D01*
X569879Y-97824D01*
G01X590436Y-113865D02*
Y-96365D01*
X587816Y-99865D01*
G01Y-113865D02*
X593056D01*
G01X603133Y-110365D02*
X604442Y-112407D01*
X606189Y-113573D01*
X608154Y-113865D01*
X609901Y-113573D01*
X611648Y-112115D01*
X612739Y-110365D01*
X612958Y-108615D01*
X612521Y-106574D01*
X610993Y-105115D01*
X609464Y-104532D01*
X607499D01*
G01X609464D02*
X610774Y-103657D01*
X611866Y-102199D01*
X612303Y-100449D01*
X611866Y-98698D01*
X610774Y-97240D01*
X608809Y-96365D01*
X606844Y-96657D01*
X604879Y-97824D01*
G01X625436Y-96365D02*
X623689Y-96948D01*
X622379Y-98407D01*
X621506Y-100156D01*
X620851Y-102490D01*
X620633Y-105115D01*
X620851Y-107740D01*
X621506Y-110074D01*
X622379Y-111824D01*
X623689Y-113282D01*
X625436Y-113865D01*
X627182Y-113282D01*
X628493Y-111824D01*
X629366Y-110074D01*
X630021Y-107740D01*
X630239Y-105115D01*
X630021Y-102490D01*
X629366Y-100156D01*
X628493Y-98407D01*
X627182Y-96948D01*
X625436Y-96365D01*
G01X685027Y-51365D02*
X690486Y-68865D01*
X695945Y-51365D01*
G01X712353Y-68865D02*
X703619D01*
Y-51365D01*
X712353D01*
G01X708859Y-59823D02*
X703619D01*
G01X721119Y-68865D02*
Y-51365D01*
X726578D01*
X728324Y-52240D01*
X729416Y-53407D01*
X729853Y-55740D01*
X729416Y-58074D01*
X728106Y-59532D01*
X726578Y-60407D01*
X721119D01*
G01X726578D02*
X729853Y-68865D01*
G01X742986Y-69448D02*
X742549Y-69157D01*
Y-68573D01*
X742986Y-68282D01*
X743423Y-68573D01*
Y-69157D01*
X742986Y-69448D01*
G01X707986Y-113865D02*
Y-96365D01*
X705366Y-99865D01*
G01Y-113865D02*
X710606D01*
G01X727232Y-104532D02*
X728106Y-103657D01*
X728761Y-102199D01*
X729198Y-100156D01*
X728761Y-98407D01*
X727888Y-97240D01*
X726359Y-96365D01*
X720464D01*
Y-113865D01*
X727669D01*
X729198Y-112699D01*
X730071Y-110948D01*
X730508Y-108907D01*
X730071Y-106865D01*
X728761Y-105115D01*
X727232Y-104532D01*
X720464D01*
G01X818569Y-51365D02*
Y-68865D01*
X827303D01*
G01X844366D02*
Y-57199D01*
G01Y-59240D02*
X843493Y-58074D01*
X842182Y-57490D01*
X840654Y-57199D01*
X839126Y-57782D01*
X837816Y-58948D01*
X836942Y-60698D01*
X836506Y-63032D01*
X836942Y-65365D01*
X837816Y-67115D01*
X839126Y-68282D01*
X840654Y-68865D01*
X842182Y-68573D01*
X843493Y-67699D01*
X844366Y-66532D01*
G01X853351Y-74115D02*
X854661Y-74698D01*
X856408Y-74115D01*
X857499Y-72949D01*
X858373Y-71490D01*
X859682Y-66824D01*
X862521Y-57199D01*
G01X855534D02*
X859682Y-66824D01*
G01X872161Y-60990D02*
X879148D01*
X878493Y-58948D01*
X877401Y-57782D01*
X875873Y-57199D01*
X874344Y-57490D01*
X873034Y-58365D01*
X872161Y-60407D01*
X871724Y-62157D01*
Y-63907D01*
X872161Y-65657D01*
X873253Y-67407D01*
X874563Y-68573D01*
X876091Y-68865D01*
X877619Y-68282D01*
X879148Y-66532D01*
G01X889879Y-68865D02*
Y-57199D01*
G01Y-59532D02*
X890971Y-58365D01*
X892063Y-57490D01*
X893591Y-57199D01*
X894682Y-57490D01*
X895993Y-58365D01*
G01X844819Y-96365D02*
Y-113865D01*
X853553D01*
G01X861883Y-111241D02*
X863192Y-112699D01*
X864721Y-113573D01*
X866686Y-113865D01*
X868651Y-113282D01*
X870179Y-112115D01*
X871271Y-110074D01*
X871489Y-107740D01*
X871053Y-105407D01*
X869961Y-103948D01*
X868432Y-102782D01*
X866904Y-102490D01*
X865376Y-102782D01*
X863411Y-103948D01*
X864066Y-96365D01*
X869961D01*
G01X943619Y-110365D02*
X944711Y-112115D01*
X946021Y-113282D01*
X947549Y-113865D01*
X949296Y-113282D01*
X950606Y-112115D01*
X951916Y-110365D01*
X952353Y-108032D01*
Y-96365D01*
G01X965486Y-113865D02*
X963739Y-113573D01*
X962211Y-112407D01*
X960901Y-110657D01*
X960027Y-108615D01*
X959591Y-106282D01*
Y-103948D01*
X960027Y-101615D01*
X960901Y-99573D01*
X962211Y-97824D01*
X963739Y-96657D01*
X965486Y-96365D01*
X967232Y-96657D01*
X968761Y-97824D01*
X970071Y-99573D01*
X970945Y-101615D01*
X971381Y-103948D01*
Y-106282D01*
X970945Y-108615D01*
X970071Y-110657D01*
X968761Y-112407D01*
X967232Y-113573D01*
X965486Y-113865D01*
G01X978401Y-111532D02*
X980148Y-112990D01*
X982113Y-113865D01*
X983859D01*
X985606Y-112990D01*
X986916Y-111532D01*
X987571Y-109490D01*
X987134Y-107449D01*
X986043Y-105698D01*
X984078Y-104532D01*
X981458Y-103948D01*
X979929Y-102782D01*
X979274Y-100740D01*
X979711Y-98698D01*
X980803Y-97240D01*
X982331Y-96365D01*
X983859D01*
X985388Y-96948D01*
X986698Y-98407D01*
G01X1004853Y-113865D02*
X996119D01*
Y-96365D01*
X1004853D01*
G01X1001359Y-104823D02*
X996119D01*
G01X1013619Y-113865D02*
Y-96365D01*
X1018859D01*
X1020606Y-97240D01*
X1021916Y-99282D01*
X1022353Y-101615D01*
X1021916Y-103948D01*
X1020824Y-105698D01*
X1018859Y-106574D01*
X1013619D01*
G01X1030901Y-113865D02*
Y-96365D01*
G01X1040071D02*
Y-113865D01*
G01Y-105115D02*
X1030901D01*
G01X1066119Y-96365D02*
Y-113865D01*
X1074853D01*
G01X1082527D02*
X1087986Y-96365D01*
X1093445Y-113865D01*
G01X1091479Y-107740D02*
X1084492D01*
G01X1100683Y-96365D02*
Y-108907D01*
X1101556Y-111532D01*
X1103303Y-113282D01*
X1105486Y-113865D01*
X1107669Y-113282D01*
X1109416Y-111532D01*
X1110289Y-108907D01*
Y-96365D01*
G01X960683Y-68865D02*
Y-51365D01*
X965049D01*
X966796Y-52240D01*
X968106Y-53407D01*
X969198Y-55156D01*
X970071Y-57199D01*
X970289Y-60115D01*
X970071Y-63032D01*
X969198Y-65074D01*
X968106Y-66824D01*
X966796Y-67990D01*
X965049Y-68865D01*
X960683D01*
G01X979711Y-60990D02*
X986698D01*
X986043Y-58948D01*
X984951Y-57782D01*
X983423Y-57199D01*
X981894Y-57490D01*
X980584Y-58365D01*
X979711Y-60407D01*
X979274Y-62157D01*
Y-63907D01*
X979711Y-65657D01*
X980803Y-67407D01*
X982113Y-68573D01*
X983641Y-68865D01*
X985169Y-68282D01*
X986698Y-66532D01*
G01X997211Y-66824D02*
X998303Y-67990D01*
X999831Y-68865D01*
X1001141D01*
X1002451Y-68282D01*
X1003324Y-67407D01*
X1003761Y-66241D01*
X1003543Y-64490D01*
X1002669Y-63615D01*
X998739Y-61865D01*
X997866Y-59823D01*
X998303Y-58365D01*
X999176Y-57490D01*
X1000486Y-57199D01*
X1001796Y-57490D01*
X1003106Y-58365D01*
G01X1017986Y-57199D02*
Y-68865D01*
G01Y-52532D02*
X1017549Y-52240D01*
Y-51657D01*
X1017986Y-51365D01*
X1018423Y-51657D01*
Y-52240D01*
X1017986Y-52532D01*
G01X1032429Y-73240D02*
X1033958Y-74407D01*
X1035704Y-74698D01*
X1037232Y-74407D01*
X1038543Y-72949D01*
X1039416Y-70907D01*
Y-57199D01*
G01Y-59532D02*
X1038543Y-58365D01*
X1037232Y-57490D01*
X1035704Y-57199D01*
X1033958Y-57782D01*
X1032866Y-58948D01*
X1031992Y-60990D01*
X1031556Y-63032D01*
X1031774Y-64782D01*
X1032648Y-66824D01*
X1033958Y-68282D01*
X1035704Y-68865D01*
X1037014Y-68573D01*
X1038543Y-67407D01*
X1039416Y-66241D01*
G01X1049274Y-68865D02*
Y-57199D01*
G01Y-60115D02*
X1050148Y-58657D01*
X1051458Y-57490D01*
X1053204Y-57199D01*
X1054732Y-57490D01*
X1056043Y-58657D01*
X1056698Y-60698D01*
Y-68865D01*
G01X1067211Y-60990D02*
X1074198D01*
X1073543Y-58948D01*
X1072451Y-57782D01*
X1070923Y-57199D01*
X1069394Y-57490D01*
X1068084Y-58365D01*
X1067211Y-60407D01*
X1066774Y-62157D01*
Y-63907D01*
X1067211Y-65657D01*
X1068303Y-67407D01*
X1069613Y-68573D01*
X1071141Y-68865D01*
X1072669Y-68282D01*
X1074198Y-66532D01*
G01X1084929Y-68865D02*
Y-57199D01*
G01Y-59532D02*
X1086021Y-58365D01*
X1087113Y-57490D01*
X1088641Y-57199D01*
X1089732Y-57490D01*
X1091043Y-58365D01*
G01X1131686Y-113865D02*
Y-96365D01*
X1129066Y-99865D01*
G01Y-113865D02*
X1134306D01*
G01X1149186D02*
Y-96365D01*
X1146566Y-99865D01*
G01Y-113865D02*
X1151806D01*
G01X1162756Y-114448D02*
X1170616Y-96365D01*
G01X1184186Y-113865D02*
Y-96365D01*
X1181566Y-99865D01*
G01Y-113865D02*
X1186806D01*
G01X1196883Y-110365D02*
X1198192Y-112407D01*
X1199939Y-113573D01*
X1201904Y-113865D01*
X1203651Y-113573D01*
X1205398Y-112115D01*
X1206489Y-110365D01*
X1206708Y-108615D01*
X1206271Y-106574D01*
X1204743Y-105115D01*
X1203214Y-104532D01*
X1201249D01*
G01X1203214D02*
X1204524Y-103657D01*
X1205616Y-102199D01*
X1206053Y-100449D01*
X1205616Y-98698D01*
X1204524Y-97240D01*
X1202559Y-96365D01*
X1200594Y-96657D01*
X1198629Y-97824D01*
G01X1215256Y-114448D02*
X1223116Y-96365D01*
G01X1232538Y-99282D02*
X1233848Y-97532D01*
X1235376Y-96657D01*
X1237123Y-96365D01*
X1239306Y-96948D01*
X1240834Y-98407D01*
X1241271Y-100156D01*
X1241053Y-101907D01*
X1240179Y-103365D01*
X1235813Y-106282D01*
X1233848Y-108323D01*
X1232538Y-111241D01*
X1232101Y-113865D01*
X1241271D01*
G01X1254186Y-96365D02*
X1252439Y-96948D01*
X1251129Y-98407D01*
X1250256Y-100156D01*
X1249601Y-102490D01*
X1249383Y-105115D01*
X1249601Y-107740D01*
X1250256Y-110074D01*
X1251129Y-111824D01*
X1252439Y-113282D01*
X1254186Y-113865D01*
X1255932Y-113282D01*
X1257243Y-111824D01*
X1258116Y-110074D01*
X1258771Y-107740D01*
X1258989Y-105115D01*
X1258771Y-102490D01*
X1258116Y-100156D01*
X1257243Y-98407D01*
X1255932Y-96948D01*
X1254186Y-96365D01*
G01X1271686Y-113865D02*
Y-96365D01*
X1269066Y-99865D01*
G01Y-113865D02*
X1274306D01*
G01X1291806D02*
Y-96365D01*
X1283727Y-108907D01*
X1294645D01*
G01X1179383Y-68865D02*
Y-51365D01*
X1183749D01*
X1185496Y-52240D01*
X1186806Y-53407D01*
X1187898Y-55156D01*
X1188771Y-57199D01*
X1188989Y-60115D01*
X1188771Y-63032D01*
X1187898Y-65074D01*
X1186806Y-66824D01*
X1185496Y-67990D01*
X1183749Y-68865D01*
X1179383D01*
G01X1205616D02*
Y-57199D01*
G01Y-59240D02*
X1204743Y-58074D01*
X1203432Y-57490D01*
X1201904Y-57199D01*
X1200376Y-57782D01*
X1199066Y-58948D01*
X1198192Y-60698D01*
X1197756Y-63032D01*
X1198192Y-65365D01*
X1199066Y-67115D01*
X1200376Y-68282D01*
X1201904Y-68865D01*
X1203432Y-68573D01*
X1204743Y-67699D01*
X1205616Y-66532D01*
G01X1219186Y-51365D02*
Y-68865D01*
G01X1216129Y-57199D02*
X1222243D01*
G01X1233411Y-60990D02*
X1240398D01*
X1239743Y-58948D01*
X1238651Y-57782D01*
X1237123Y-57199D01*
X1235594Y-57490D01*
X1234284Y-58365D01*
X1233411Y-60407D01*
X1232974Y-62157D01*
Y-63907D01*
X1233411Y-65657D01*
X1234503Y-67407D01*
X1235813Y-68573D01*
X1237341Y-68865D01*
X1238869Y-68282D01*
X1240398Y-66532D01*
G01X389150Y234297D02*
X387319Y236128D01*
Y240653D01*
X409309Y262643D01*
X425537D01*
X428369Y265475D01*
X466478D01*
X478253Y253700D01*
X481200D01*
X482600Y255100D01*
X486900D01*
X488300Y253700D01*
X503500D01*
X508100Y249100D01*
X531500D01*
X533448Y251048D01*
Y253448D01*
X534700Y254700D01*
Y256900D01*
X531300Y260300D01*
Y261727D01*
X530700Y262327D01*
X530000D01*
X529400Y262927D01*
Y264127D01*
X530000Y264727D01*
X530700D01*
X531300Y265327D01*
Y266527D01*
X530700Y267127D01*
X530100D01*
X529500Y267727D01*
Y268927D01*
X530100Y269527D01*
X530700D01*
X531300Y270127D01*
Y272426D01*
X530900Y272826D01*
Y273000D01*
G01X531775Y252231D02*
X531604D01*
X529797Y250424D01*
X513776D01*
X506900Y257300D01*
X505605D01*
X505005Y257900D01*
Y261200D01*
X504405Y261800D01*
X503205D01*
X502605Y261200D01*
Y257900D01*
X502005Y257300D01*
X500805D01*
X500205Y257900D01*
Y263000D01*
X499605Y263600D01*
X498405D01*
X497805Y263000D01*
Y257900D01*
X497205Y257300D01*
X490700D01*
X485500Y262500D01*
X472706D01*
X467431Y267775D01*
X427416D01*
X424584Y264943D01*
X408356D01*
X385019Y241606D01*
Y235175D01*
X386100Y234094D01*
G01X530015Y255000D02*
X530000Y255015D01*
Y255500D01*
X528365Y257135D01*
Y259435D01*
X527200Y260600D01*
X514681D01*
X514081Y261200D01*
Y269500D01*
X513481Y270100D01*
X512281D01*
X511681Y269500D01*
Y261200D01*
X511081Y260600D01*
X509100D01*
X499625Y270075D01*
X426463D01*
X423631Y267243D01*
X407403D01*
X382719Y242559D01*
G01X552800Y14807D02*
Y17800D01*
X542543Y28057D01*
X521750D01*
X508107Y41700D01*
X491600D01*
X488700Y38800D01*
X451179D01*
X429079Y60900D01*
X407051D01*
X390600Y77351D01*
G01X549500Y31607D02*
X549400Y31707D01*
Y36700D01*
X547100Y39000D01*
X529400D01*
X528800Y39600D01*
Y43750D01*
X528200Y44350D01*
X526100D01*
X525500Y43750D01*
Y41100D01*
X524900Y40500D01*
X523700D01*
X523100Y41100D01*
Y43750D01*
X522500Y44350D01*
X521300D01*
X520700Y43750D01*
Y40900D01*
X520100Y40300D01*
X518900D01*
X518300Y40900D01*
Y43750D01*
X517700Y44350D01*
X490050D01*
X486800Y41100D01*
X452132D01*
X430032Y63200D01*
X408005D01*
X393900Y77305D01*
G01X394100Y80358D02*
X408958Y65500D01*
X430985D01*
X446785Y49700D01*
X517900D01*
X518500Y49100D01*
Y47500D01*
X519100Y46900D01*
X528300D01*
X528900Y47500D01*
Y49900D01*
X529500Y50500D01*
X530700D01*
X531300Y49900D01*
Y46600D01*
X531900Y46000D01*
X533100D01*
X533700Y46600D01*
Y47200D01*
X534300Y47800D01*
X535600D01*
X536200Y47200D01*
Y44200D01*
X535600Y43600D01*
X532500D01*
X531900Y43000D01*
Y41900D01*
X532500Y41300D01*
X547064D01*
X551300Y37064D01*
Y32491D01*
X553079Y30712D01*
G01X550000Y12507D02*
Y12707D01*
X537417Y25290D01*
X528319D01*
X527719Y24690D01*
Y22907D01*
X527119Y22307D01*
X525919D01*
X525319Y22907D01*
Y24690D01*
X524719Y25290D01*
X520717D01*
X518200Y27807D01*
X507200D01*
X504000Y31007D01*
Y37400D01*
X502300Y39100D01*
X493100D01*
X490500Y36500D01*
X450226D01*
X428126Y58600D01*
X406098D01*
X389000Y75698D01*
G01X570852Y33204D02*
X572101Y34453D01*
Y76999D01*
X570500Y78600D01*
X539500D01*
X538900Y78000D01*
Y74200D01*
X538300Y73600D01*
X530000D01*
X529400Y74200D01*
Y77400D01*
X528800Y78000D01*
X526500D01*
X525900Y77400D01*
Y74200D01*
X525300Y73600D01*
X524100D01*
X523500Y74200D01*
Y77200D01*
X522900Y77800D01*
X521700D01*
X521100Y77200D01*
Y74200D01*
X520500Y73600D01*
X519300D01*
X518700Y74200D01*
Y77200D01*
X518100Y77800D01*
X516900D01*
X516300Y77200D01*
Y74200D01*
X515700Y73600D01*
X514500D01*
X513900Y74200D01*
Y77200D01*
X513300Y77800D01*
X496700D01*
X496100Y77200D01*
Y74100D01*
X495600Y73600D01*
X494200D01*
X493700Y74100D01*
Y77200D01*
X493100Y77800D01*
X488700D01*
X487900Y78600D01*
X450891D01*
X441191Y88300D01*
X418200D01*
X416600Y89900D01*
Y99408D01*
X411454Y104554D01*
X397246D01*
X391788Y110012D01*
G01X581450Y30707D02*
Y30823D01*
X582100Y31473D01*
Y35152D01*
X582500Y35552D01*
Y87688D01*
X578144Y92044D01*
X496619D01*
X495675Y91100D01*
Y90300D01*
X495075Y89700D01*
X493275D01*
X492675Y90300D01*
Y91500D01*
X492075Y92100D01*
X490275D01*
X489675Y91500D01*
Y90100D01*
X489075Y89500D01*
X487000D01*
X486400Y90100D01*
Y91500D01*
X485800Y92100D01*
X471411D01*
X470811Y91500D01*
Y90200D01*
X470211Y89600D01*
X469011D01*
X468411Y90200D01*
Y91500D01*
X467811Y92100D01*
X452053D01*
X447353Y96800D01*
X433407D01*
X428207Y102000D01*
X426432D01*
X422331Y106100D01*
X420721D01*
X415721Y111100D01*
X407000D01*
X402903Y115197D01*
Y117205D01*
X402154Y117954D01*
G01X585179Y30867D02*
X583900Y32146D01*
Y34379D01*
X584860Y35339D01*
Y88581D01*
X583421Y90021D01*
X579221Y94221D01*
X579220D01*
X579041Y94400D01*
X453100D01*
X449000Y98500D01*
X433122D01*
X428622Y103000D01*
X426900D01*
X422650Y107250D01*
X420986D01*
X415436Y112800D01*
X409700D01*
X407750Y113550D01*
X407000Y114300D01*
Y116147D01*
X406396Y118279D01*
G03X405000Y120300I-2161J0D01*
G01X402500Y121086D01*
X401902D01*
G01X573357Y262489D02*
X574500Y261346D01*
Y250453D01*
X573403Y249356D01*
Y247703D01*
X572900Y247200D01*
Y245503D01*
X573403Y245000D01*
Y242059D01*
X571730Y240386D01*
X571037D01*
X569764Y239113D01*
Y238420D01*
X568644Y237300D01*
X566100D01*
X565000Y238400D01*
X562300D01*
X561800Y237900D01*
X561799D01*
X561027Y237128D01*
Y234717D01*
X561700Y234044D01*
Y231456D01*
X560844Y230600D01*
X558156D01*
X553870Y234886D01*
X552041D01*
X550546Y233391D01*
Y231631D01*
X552600Y229577D01*
Y229544D01*
X555350Y226794D01*
Y225406D01*
X554356Y224412D01*
X552811D01*
X548069Y229154D01*
X546309D01*
X544814Y227659D01*
Y224114D01*
X543900Y223200D01*
X430944D01*
X428544Y220800D01*
X427856D01*
X426180Y222476D01*
X424598D01*
X422052Y219930D01*
Y218348D01*
X423022Y217378D01*
Y215778D01*
X421526Y214282D01*
X419782D01*
X417500Y212000D01*
X414544D01*
X408701Y206157D01*
X403186D01*
X400514Y203485D01*
X393485D01*
X392400Y202400D01*
Y198346D01*
X391563Y197509D01*
G01X580200Y273000D02*
X578400Y271200D01*
Y269310D01*
X579100Y268610D01*
Y265630D01*
X579700Y265030D01*
X583300D01*
X583900Y264430D01*
Y263100D01*
X583300Y262500D01*
X582300D01*
X581700Y261900D01*
Y259600D01*
X583950Y257350D01*
Y236704D01*
X583200Y235954D01*
Y233353D01*
X568447Y218600D01*
X563492D01*
X559687Y214795D01*
X547396D01*
X545601Y213000D01*
X537600D01*
X536600Y214000D01*
X535306D01*
X534306Y213000D01*
X521493D01*
X520493Y214000D01*
X518500D01*
X517500Y213000D01*
X513316D01*
X511316Y215000D01*
X509000D01*
X506000Y212000D01*
X504500D01*
X503000Y213500D01*
X501500D01*
X500000Y212000D01*
X498500D01*
X497000Y213500D01*
X495826D01*
X494326Y212000D01*
X490020D01*
X488220Y213800D01*
X469021D01*
X468121Y214700D01*
X430700D01*
X429500Y213500D01*
Y211189D01*
X425260Y206949D01*
X425253D01*
X424504Y206200D01*
X420000D01*
X417600Y203800D01*
X414200D01*
X409523Y199123D01*
X403477D01*
X400417Y196063D01*
Y189875D01*
G01X579205Y254850D02*
X580800Y256445D01*
Y259000D01*
X580200Y259600D01*
X577200D01*
X576600Y259000D01*
Y248000D01*
X577200Y247400D01*
X579850D01*
X580450Y246800D01*
Y244450D01*
X579750Y243750D01*
X577250D01*
X576600Y243100D01*
Y240900D01*
X577000Y240500D01*
X578800D01*
X579300Y240000D01*
Y238015D01*
X578586Y237301D01*
X575350D01*
X574450Y238200D01*
X573602D01*
X572752Y237350D01*
Y236502D01*
X573927Y235328D01*
Y234480D01*
X573077Y233630D01*
X572229D01*
X571054Y234804D01*
X570206D01*
X569356Y233954D01*
Y233106D01*
X570531Y231932D01*
Y231084D01*
X569681Y230234D01*
X568833D01*
X567658Y231408D01*
X566810D01*
X565960Y230558D01*
Y229710D01*
X567135Y228536D01*
Y227688D01*
X565347Y225900D01*
X563412D01*
X562612Y225100D01*
X560500D01*
X558750Y223350D01*
Y221461D01*
X556684Y219395D01*
X534195D01*
X532400Y217600D01*
X529322D01*
X528722Y218200D01*
Y219200D01*
X528122Y219800D01*
X526400D01*
X525800Y219200D01*
Y218200D01*
X525200Y217600D01*
X523400D01*
X522800Y218200D01*
Y219200D01*
X522200Y219800D01*
X431700D01*
X430200Y218300D01*
X427400D01*
X425700Y216600D01*
Y213200D01*
X421800Y209300D01*
X415800D01*
X409450Y202950D01*
X402950D01*
X397500Y197500D01*
G01X582200Y252206D02*
Y239500D01*
X579394Y236694D01*
Y235846D01*
X580396Y234844D01*
Y233996D01*
X579546Y233146D01*
X578698D01*
X577696Y234148D01*
X576848D01*
X575998Y233298D01*
Y232450D01*
X577050Y231398D01*
Y230550D01*
X576200Y229700D01*
X575352D01*
X574360Y230692D01*
X573512D01*
X572662Y229842D01*
Y228994D01*
X573704Y227952D01*
Y227110D01*
X572848Y226254D01*
X572006D01*
X570904Y227356D01*
X570056D01*
X567300Y224600D01*
Y221800D01*
X566400Y220900D01*
X562539D01*
X558734Y217095D01*
X545848D01*
X545248Y216495D01*
Y215900D01*
X544648Y215300D01*
X543448D01*
X542848Y215900D01*
Y216495D01*
X542248Y217095D01*
X541048D01*
X540448Y216495D01*
Y215900D01*
X539848Y215300D01*
X538648D01*
X538048Y215900D01*
Y216495D01*
X537448Y217095D01*
X535148D01*
X533353Y215300D01*
X522447D01*
X520447Y217300D01*
X518300D01*
X517000Y216000D01*
X515000D01*
X513700Y217300D01*
X501500D01*
X499700Y215500D01*
X498500D01*
X496700Y217300D01*
X494573D01*
X493973Y216700D01*
Y214900D01*
X493373Y214300D01*
X492173D01*
X491573Y214900D01*
Y216700D01*
X490973Y217300D01*
X488393D01*
X487193Y216100D01*
X485993D01*
X484793Y217300D01*
X483593D01*
X482393Y216100D01*
X481193D01*
X479993Y217300D01*
X478793D01*
X477593Y216100D01*
X476393D01*
X475193Y217300D01*
X473993D01*
X472793Y216100D01*
X471593D01*
X470393Y217300D01*
X427815D01*
X426700Y216185D01*
Y212785D01*
X422215Y208300D01*
X419597D01*
X416996Y205699D01*
X413899D01*
X409534Y201334D01*
X404065D01*
X400545Y197814D01*
G01X576642Y262489D02*
X575600Y261447D01*
Y249997D01*
X574503Y248900D01*
Y241603D01*
X569100Y236200D01*
X565644D01*
X564544Y237300D01*
X562756D01*
X562128Y236672D01*
Y235172D01*
X562800Y234500D01*
Y231000D01*
X561300Y229500D01*
X557700D01*
X553414Y233786D01*
X552497D01*
X551646Y232935D01*
Y232087D01*
X553700Y230033D01*
Y230000D01*
X556450Y227250D01*
Y224950D01*
X554812Y223312D01*
X552355D01*
X547613Y228054D01*
X546765D01*
X545914Y227203D01*
Y223658D01*
X544356Y222100D01*
X431400D01*
X429000Y219700D01*
X427400D01*
X425724Y221376D01*
X425054D01*
X423152Y219474D01*
Y218804D01*
X424122Y217834D01*
Y215322D01*
X421982Y213182D01*
X420238D01*
X417956Y210900D01*
X415000D01*
X409157Y205057D01*
X403642D01*
X400970Y202385D01*
X393941D01*
X393500Y201944D01*
Y197890D01*
X392341Y196731D01*
G01X571867Y254685D02*
X570450Y253268D01*
Y251050D01*
X571300Y250200D01*
Y249200D01*
X569850Y247750D01*
Y245450D01*
X571300Y244000D01*
Y242624D01*
X569276Y240600D01*
X567400D01*
X566800Y241200D01*
Y249400D01*
X566200Y250000D01*
X564400D01*
X563800Y249400D01*
Y240800D01*
X563200Y240200D01*
X560600D01*
X560000Y240800D01*
Y243800D01*
X559400Y244400D01*
X555515D01*
X554850Y243735D01*
Y241250D01*
X557600Y238500D01*
Y237000D01*
X556600Y236000D01*
X555200D01*
X553175Y238025D01*
X551825D01*
X548246Y234446D01*
Y232254D01*
X547446Y231454D01*
X545254D01*
X542500Y228700D01*
X540400D01*
X539800Y228100D01*
Y226100D01*
X539200Y225500D01*
X537000D01*
X536400Y226100D01*
Y227400D01*
X535800Y228000D01*
X533500D01*
X532900Y227400D01*
Y226100D01*
X532300Y225500D01*
X530500D01*
X528000Y228000D01*
X525200D01*
X524600Y227400D01*
Y226100D01*
X524000Y225500D01*
X427900D01*
X426500Y224100D01*
X424100D01*
X422700Y225500D01*
X420600D01*
X419900Y226200D01*
X418400D01*
X417750Y225550D01*
Y214800D01*
X416400Y213450D01*
X414250D01*
X412900Y212100D01*
X411500D01*
X410200Y210800D01*
Y209400D01*
X408993Y208193D01*
X403807D01*
X400214Y204600D01*
X395700D01*
X395100Y205200D01*
Y205800D01*
X394500Y206400D01*
X391700D01*
X391100Y205800D01*
Y203000D01*
X389047Y200947D01*
Y200000D01*
G01X387590Y201990D02*
X389000Y203400D01*
Y206600D01*
X390100Y207700D01*
X396100D01*
X397350Y206450D01*
X400250D01*
X404300Y210500D01*
X407400D01*
X413900Y217000D01*
Y225350D01*
X416350Y227800D01*
X521747D01*
X524247Y230300D01*
X537500D01*
X538900Y231700D01*
X542200D01*
X551950Y241450D01*
Y243950D01*
X553100Y245100D01*
X554800D01*
X556200Y246500D01*
X558900D01*
X560300Y245100D01*
X562000D01*
X562600Y245700D01*
Y249787D01*
X562000Y250387D01*
X559200D01*
X558600Y250987D01*
Y259400D01*
X561117Y261917D01*
Y263983D01*
X562234Y265100D01*
X563678D01*
X564278Y264500D01*
Y261000D01*
X564878Y260400D01*
X566678D01*
X567278Y261000D01*
Y264400D01*
X567878Y265000D01*
X569400D01*
X570000Y264400D01*
Y262000D01*
X571200Y260800D01*
X572500D01*
X573500Y259800D01*
Y258300D01*
X572900Y257700D01*
X567000D01*
X566400Y257100D01*
Y255761D01*
X568327Y253834D01*
Y253348D01*
G01X541500Y270900D02*
X542437Y269963D01*
Y260163D01*
X547200Y255400D01*
Y251800D01*
X534300Y238900D01*
X510800D01*
X510200Y238300D01*
X454700D01*
X454100Y238900D01*
Y241500D01*
X453500Y242100D01*
X452300D01*
X451700Y241500D01*
Y238900D01*
X451100Y238300D01*
X449900D01*
X449300Y238900D01*
Y242600D01*
X448700Y243200D01*
X447500D01*
X446900Y242600D01*
Y238900D01*
X446300Y238300D01*
X445100D01*
X444500Y238900D01*
Y242600D01*
X443900Y243200D01*
X440400D01*
X438500Y241300D01*
X415100D01*
X406900Y233100D01*
X402900D01*
X399700Y229900D01*
Y225000D01*
G01X395600Y224400D02*
Y229300D01*
X402000Y235700D01*
X402976D01*
X409238Y241962D01*
Y242031D01*
X411356Y244149D01*
Y250156D01*
X413200Y252000D01*
X426209D01*
X431309Y257100D01*
X448500D01*
X449100Y256500D01*
Y252600D01*
X449699Y252001D01*
X451652D01*
X451653Y252000D01*
X453800D01*
X454400Y251400D01*
Y250300D01*
X455000Y249700D01*
X458500D01*
X459100Y250300D01*
Y253900D01*
X458500Y254500D01*
X453300D01*
X452700Y255100D01*
Y256425D01*
X453375Y257100D01*
X462838D01*
X477038Y242900D01*
X534034D01*
X542850Y251716D01*
Y252950D01*
X541005Y254795D01*
Y254800D01*
G01X538847Y262489D02*
X537800Y261443D01*
Y260300D01*
X539200Y258900D01*
Y250844D01*
X533556Y245200D01*
X477991D01*
X463791Y259400D01*
X430356D01*
X425256Y254300D01*
X411700D01*
X409056Y251656D01*
Y245102D01*
X407300Y243346D01*
X407293D01*
X392950Y229003D01*
Y223194D01*
G01X535562Y262489D02*
X536700Y261351D01*
Y259844D01*
X538100Y258444D01*
Y251300D01*
X533100Y246300D01*
X492759D01*
X492269Y246790D01*
X490469D01*
X489979Y246300D01*
X487607D01*
X487117Y246790D01*
X485317D01*
X484827Y246300D01*
X483027D01*
X482537Y246790D01*
X480737D01*
X480247Y246300D01*
X478447D01*
X464247Y260500D01*
X429900D01*
X424800Y255400D01*
X422416D01*
X421926Y255890D01*
X420126D01*
X419636Y255400D01*
X417836D01*
X417346Y255890D01*
X415546D01*
X415056Y255400D01*
X411244D01*
X407956Y252112D01*
Y250138D01*
X407466Y249648D01*
Y247848D01*
X407956Y247358D01*
Y245558D01*
X406844Y244446D01*
X406837D01*
X403312Y240921D01*
X402619D01*
X401346Y239648D01*
Y238955D01*
X400073Y237682D01*
X399380D01*
X398108Y236410D01*
Y235717D01*
X396835Y234444D01*
X396142D01*
X394869Y233171D01*
Y232478D01*
X391850Y229459D01*
Y223850D01*
G01X544800Y255100D02*
Y254672D01*
X543850Y253722D01*
Y251079D01*
X533371Y240600D01*
X457600D01*
X457000Y241200D01*
Y246800D01*
X456400Y247400D01*
X454047D01*
X452247Y249200D01*
X434700D01*
X434100Y249800D01*
Y251400D01*
X434700Y252000D01*
X441400D01*
X442000Y252600D01*
Y254200D01*
X441400Y254800D01*
X432262D01*
X427162Y249700D01*
X415300D01*
X413656Y248056D01*
Y243127D01*
X405029Y234500D01*
X402500D01*
X397700Y229700D01*
Y219100D01*
X395700Y217100D01*
Y217000D01*
G01X399700Y216400D02*
X402100Y218800D01*
Y229800D01*
X404000Y231700D01*
X408768D01*
X413068Y236000D01*
X419400D01*
X420000Y236600D01*
Y238400D01*
X420600Y239000D01*
X421800D01*
X422400Y238400D01*
Y236600D01*
X423000Y236000D01*
X424200D01*
X424800Y236600D01*
Y238400D01*
X425400Y239000D01*
X426600D01*
X427200Y238400D01*
Y236600D01*
X427800Y236000D01*
X429000D01*
X429600Y236600D01*
Y238400D01*
X430200Y239000D01*
X431400D01*
X432000Y238400D01*
Y236600D01*
X432600Y236000D01*
X433800D01*
X434400Y236600D01*
Y238100D01*
X435000Y238700D01*
X436200D01*
X436800Y238100D01*
Y236600D01*
X437400Y236000D01*
X511300D01*
X512400Y237100D01*
X534500D01*
X548300Y250900D01*
Y258285D01*
X546522Y260063D01*
X544200D01*
X543600Y260663D01*
Y272528D01*
X544200Y273128D01*
X544292D01*
G01X534100Y270700D02*
X533037Y269637D01*
Y261063D01*
X536900Y257200D01*
Y251900D01*
X532800Y247800D01*
X502800D01*
X499300Y251300D01*
X495400D01*
X493600Y249500D01*
X479200D01*
X465525Y263175D01*
X429322D01*
X426490Y260343D01*
X410262D01*
X389619Y239700D01*
Y237081D01*
X390900Y235800D01*
G01X557745Y22907D02*
X557600D01*
X557000Y23507D01*
Y26607D01*
X556000Y27607D01*
Y37756D01*
X549056Y44700D01*
X543888D01*
X534488Y54100D01*
X526444D01*
X525300Y52956D01*
Y50700D01*
X524700Y50100D01*
X522400D01*
X521800Y50700D01*
Y51856D01*
X520556Y53100D01*
X515298D01*
X514808Y53590D01*
X513008D01*
X512518Y53100D01*
X510718D01*
X510228Y53590D01*
X508428D01*
X507938Y53100D01*
X506138D01*
X505648Y53590D01*
X503848D01*
X503358Y53100D01*
X494085D01*
X493595Y53590D01*
X491795D01*
X491305Y53100D01*
X489505D01*
X489015Y53590D01*
X487215D01*
X486725Y53100D01*
X484925D01*
X484435Y53590D01*
X482635D01*
X482145Y53100D01*
X475152D01*
X474662Y53590D01*
X472862D01*
X472372Y53100D01*
X470572D01*
X470082Y53590D01*
X468282D01*
X467792Y53100D01*
X465992D01*
X465502Y53590D01*
X463702D01*
X463212Y53100D01*
X461400D01*
X460900Y53600D01*
X459100D01*
X458600Y53100D01*
X448194D01*
X432394Y68900D01*
X410800D01*
G01X561200Y12507D02*
Y14507D01*
X560600Y15107D01*
X559300D01*
X558700Y15707D01*
Y17407D01*
X559300Y18007D01*
X560800D01*
X561400Y18607D01*
Y25007D01*
X557600Y28807D01*
Y38600D01*
X549000Y47200D01*
X544641D01*
X535441Y56400D01*
X448747D01*
X433947Y71200D01*
X412400D01*
G01X564400Y14307D02*
Y14407D01*
X563700Y15107D01*
Y24907D01*
X559000Y29607D01*
Y32565D01*
X558985Y32580D01*
Y33948D01*
X559000Y33963D01*
Y40000D01*
X549400Y49600D01*
X545494D01*
X536394Y58700D01*
X449700D01*
X434900Y73500D01*
X411800D01*
G01X554460Y22907D02*
X555300D01*
X555900Y23507D01*
Y26151D01*
X554900Y27151D01*
Y37300D01*
X548600Y43600D01*
X543432D01*
X534032Y53000D01*
X526900D01*
X526400Y52500D01*
Y50244D01*
X525156Y49000D01*
X521944D01*
X520700Y50244D01*
Y51400D01*
X520100Y52000D01*
X447738D01*
X431938Y67800D01*
X410000D01*
G01X412300Y78600D02*
X412800Y78100D01*
X436965D01*
X446665Y68400D01*
X452000D01*
X452600Y67800D01*
Y65300D01*
X453200Y64700D01*
X454400D01*
X455000Y65300D01*
Y67800D01*
X455600Y68400D01*
X456800D01*
X457400Y67800D01*
Y65300D01*
X458000Y64700D01*
X459200D01*
X459800Y65300D01*
Y67800D01*
X460400Y68400D01*
X462800D01*
X463400Y67800D01*
Y63900D01*
X464000Y63300D01*
X548800D01*
X556050Y56050D01*
Y49450D01*
X563700Y41800D01*
Y32206D01*
X565091Y30815D01*
G01X569800Y29807D02*
Y29977D01*
X569120Y30657D01*
Y33877D01*
X569801Y34558D01*
Y74499D01*
X568000Y76300D01*
X541900D01*
X541300Y75700D01*
Y71900D01*
X540700Y71300D01*
X511600D01*
X511000Y71900D01*
Y74100D01*
X510400Y74700D01*
X509200D01*
X508600Y74100D01*
Y71900D01*
X508000Y71300D01*
X506800D01*
X506200Y71900D01*
Y74100D01*
X505600Y74700D01*
X504400D01*
X503800Y74100D01*
Y71900D01*
X503200Y71300D01*
X502000D01*
X501400Y71900D01*
Y74100D01*
X500800Y74700D01*
X499600D01*
X499000Y74100D01*
Y71900D01*
X498400Y71300D01*
X492000D01*
X491400Y71900D01*
Y74100D01*
X490800Y74700D01*
X489700D01*
X489100Y74100D01*
Y72200D01*
X488500Y71600D01*
X487300D01*
X486700Y72200D01*
Y74400D01*
X486100Y75000D01*
X484900D01*
X484300Y74400D01*
Y72200D01*
X483700Y71600D01*
X482500D01*
X481900Y72200D01*
Y75700D01*
X481300Y76300D01*
X449938D01*
X440238Y86000D01*
X416100D01*
X412900Y89200D01*
Y97100D01*
X407400Y102600D01*
G01X405496Y97104D02*
Y83104D01*
X407200Y81400D01*
X438332D01*
X448032Y71700D01*
X466100D01*
X466700Y71100D01*
Y67500D01*
X467300Y66900D01*
X469100D01*
X469700Y67500D01*
Y71100D01*
X470300Y71700D01*
X472000D01*
X472600Y71100D01*
Y67200D01*
X473200Y66600D01*
X545600D01*
X546200Y67200D01*
Y71000D01*
X546800Y71600D01*
X564025D01*
X564861Y70764D01*
Y42639D01*
X567120Y40380D01*
Y26887D01*
X568555Y25452D01*
Y12407D01*
G01X571600Y14207D02*
X570855Y14952D01*
Y25452D01*
X568120Y28187D01*
Y42460D01*
X567501Y43079D01*
Y71377D01*
X564878Y74000D01*
X545800D01*
X543700Y71900D01*
Y69600D01*
X543100Y69000D01*
X480200D01*
X479600Y69600D01*
Y73400D01*
X479000Y74000D01*
X477900D01*
X477300Y73400D01*
Y69900D01*
X476700Y69300D01*
X475500D01*
X474900Y69900D01*
Y73400D01*
X474300Y74000D01*
X448985D01*
X439285Y83700D01*
X410400D01*
X409200Y84900D01*
Y90700D01*
G01X561456Y30902D02*
Y31074D01*
X562320Y31938D01*
Y39927D01*
X553294Y48953D01*
Y48959D01*
X552261Y49992D01*
Y56400D01*
X551661Y57000D01*
X549261D01*
X548661Y56400D01*
Y53300D01*
X548061Y52700D01*
X545661D01*
X545061Y53300D01*
Y60400D01*
X544461Y61000D01*
X450700D01*
X450100Y61600D01*
Y65500D01*
X449500Y66100D01*
X445712D01*
X436012Y75800D01*
X415200D01*
G01X579800Y14807D02*
X580328Y15335D01*
Y25179D01*
X577450Y28057D01*
Y34322D01*
X577801Y34673D01*
Y80408D01*
X573909Y84300D01*
X453347D01*
X443847Y93800D01*
X433485D01*
X427385Y99900D01*
X425700D01*
X421500Y104100D01*
X418500D01*
X414382Y108218D01*
X403703D01*
X403110Y108811D01*
G01X582655Y12407D02*
X584455Y14207D01*
Y24201D01*
X579800Y28856D01*
Y31573D01*
X581000Y32773D01*
Y34607D01*
X580101Y35506D01*
Y82352D01*
X575853Y86600D01*
X574862D01*
X574861Y86601D01*
X572957D01*
X572956Y86600D01*
X461589D01*
X460989Y87200D01*
Y88000D01*
X460389Y88600D01*
X459189D01*
X458589Y88000D01*
Y87200D01*
X457989Y86600D01*
X454300D01*
X445400Y95500D01*
X433200D01*
X427800Y100900D01*
X426116D01*
X421915Y105100D01*
X419900D01*
X415374Y109625D01*
X405175D01*
X403800Y111000D01*
G01X416485Y113250D02*
X419535Y110200D01*
X421700D01*
X423700Y108200D01*
X431400D01*
X438578Y101022D01*
X451145D01*
X451167Y101000D01*
X451200D01*
X451800Y100400D01*
Y100367D01*
X453367Y98800D01*
X606247D01*
X646147Y58900D01*
X655320D01*
X666560Y47660D01*
Y17247D01*
X671290Y12517D01*
Y12457D01*
G01X582600Y270300D02*
X585500Y267400D01*
Y232400D01*
X569400Y216300D01*
X564445D01*
X560640Y212495D01*
X548349D01*
X546554Y210700D01*
X512363D01*
X511463Y211600D01*
X509087D01*
X507187Y209700D01*
X489067D01*
X487267Y211500D01*
X468067D01*
X467167Y212400D01*
X432126D01*
X425674Y205948D01*
X425667D01*
X424519Y204800D01*
X421000D01*
X418500Y202300D01*
X415300D01*
X410100Y197100D01*
Y191756D01*
G01X570200Y273100D02*
Y272300D01*
X571432Y271068D01*
X575782D01*
X576510Y270340D01*
Y267700D01*
X575360Y266550D01*
X553461D01*
X552700Y265789D01*
Y260900D01*
X553300Y260300D01*
X556100D01*
X557000Y259400D01*
Y249300D01*
X555050Y247350D01*
X550950D01*
X549135Y245535D01*
Y244687D01*
X550487Y243335D01*
Y242487D01*
X549213Y241213D01*
X548365D01*
X546463Y243115D01*
X545615D01*
X544341Y241841D01*
Y240993D01*
X546243Y239091D01*
Y238243D01*
X544969Y236969D01*
X544121D01*
X542769Y238321D01*
X541921D01*
X536200Y232600D01*
X521600D01*
X519250Y230250D01*
X507000D01*
X505750Y231500D01*
X503500D01*
X502250Y230250D01*
X500500D01*
X499250Y231500D01*
X497500D01*
X496250Y230250D01*
X414550D01*
X410300Y226000D01*
Y219000D01*
X409900Y218600D01*
Y215700D01*
X407900Y213700D01*
X405000D01*
X403171Y211871D01*
G01X567800Y270500D02*
X568000D01*
X568500Y270000D01*
Y269091D01*
X567900Y268491D01*
X554700D01*
X554100Y269091D01*
Y270200D01*
X553500Y270800D01*
X551600D01*
X550078Y269278D01*
X545600D01*
X545000Y268678D01*
Y266878D01*
X545600Y266278D01*
X550000D01*
X550600Y265678D01*
Y264600D01*
X549700Y263700D01*
X547000D01*
X546300Y263000D01*
Y261700D01*
X547200Y260800D01*
X549600D01*
X550300Y260100D01*
Y258000D01*
X550900Y257400D01*
X554400D01*
X555300Y256500D01*
Y251300D01*
X553750Y249750D01*
X550050D01*
X535200Y234900D01*
X519588D01*
X517288Y232600D01*
X512312D01*
X510812Y234100D01*
X496768D01*
X495368Y232700D01*
X417632D01*
X416232Y234100D01*
X414100D01*
X412000Y232000D01*
Y230700D01*
X410900Y229600D01*
X407500D01*
X406300Y228400D01*
Y218900D01*
X404000Y216600D01*
G01X574539Y22907D02*
X575700Y24068D01*
Y25207D01*
X574900Y26007D01*
Y33712D01*
X574401Y34211D01*
Y78999D01*
X572500Y80900D01*
X537356D01*
X536500Y80044D01*
Y77144D01*
X535256Y75900D01*
X533044D01*
X531800Y77144D01*
Y80444D01*
X531344Y80900D01*
X524500D01*
X524010Y80410D01*
X522210D01*
X521720Y80900D01*
X519920D01*
X519430Y80410D01*
X517630D01*
X517140Y80900D01*
X515340D01*
X514850Y80410D01*
X513050D01*
X512560Y80900D01*
X506760D01*
X506270Y80410D01*
X504470D01*
X503980Y80900D01*
X502180D01*
X501690Y80410D01*
X499890D01*
X499400Y80900D01*
X497600D01*
X497110Y80410D01*
X495310D01*
X494820Y80900D01*
X492823D01*
X492333Y80410D01*
X490533D01*
X490043Y80900D01*
X451844D01*
X442244Y90500D01*
X426500D01*
X424100Y92900D01*
Y98254D01*
X421463Y100891D01*
G01X577824Y22907D02*
X576800Y23931D01*
Y25663D01*
X576000Y26463D01*
Y34168D01*
X575501Y34667D01*
Y79455D01*
X572956Y82000D01*
X536900D01*
X535400Y80500D01*
Y77600D01*
X534800Y77000D01*
X533500D01*
X532900Y77600D01*
Y80900D01*
X531800Y82000D01*
X452300D01*
X442700Y91600D01*
X426956D01*
X425200Y93356D01*
Y98710D01*
X422241Y101669D01*
G01X422200Y111300D02*
X424100Y109400D01*
X431900D01*
X438700Y102600D01*
X454200D01*
X454900Y101900D01*
X606400D01*
X647100Y61200D01*
X656273D01*
X668600Y48873D01*
Y24607D01*
X673300Y19907D01*
Y15207D01*
X674288Y14219D01*
X674320D01*
G01X431700Y128300D02*
X433700Y126300D01*
X439800D01*
X444400Y121700D01*
X447300D01*
X452200Y116800D01*
X461200D01*
X462900Y118500D01*
X489100D01*
X490600Y117000D01*
X493500D01*
X494600Y118100D01*
X497000D01*
X498100Y117000D01*
X538700D01*
X539300Y117600D01*
Y119045D01*
X539900Y119645D01*
X595455D01*
X598100Y117000D01*
X621547D01*
X690000Y48547D01*
Y33093D01*
X687300Y30393D01*
Y22607D01*
X682013Y17320D01*
Y14848D01*
G01X684760Y12256D02*
X693410Y25045D01*
X695500Y30707D01*
Y34507D01*
X692600Y46709D01*
Y49700D01*
X623000Y119300D01*
X602500D01*
X599800Y122000D01*
X463600D01*
X462300Y120700D01*
X450800D01*
X441300Y130200D01*
X431400D01*
X430100Y131500D01*
G01X692250Y255700D02*
X690730Y254180D01*
Y251610D01*
X689560Y250440D01*
X668913D01*
X656786Y238313D01*
X648645D01*
X637732Y227400D01*
X635432D01*
X634832Y228000D01*
Y229300D01*
X634232Y229900D01*
X633032D01*
X632432Y229300D01*
Y228000D01*
X631832Y227400D01*
X630632D01*
X630032Y228000D01*
Y229300D01*
X629432Y229900D01*
X628232D01*
X627632Y229300D01*
Y228000D01*
X627032Y227400D01*
X612354D01*
X611754Y228000D01*
Y229000D01*
X611154Y229600D01*
X609954D01*
X609354Y229000D01*
Y228000D01*
X608754Y227400D01*
X607554D01*
X606954Y228000D01*
Y229600D01*
X606354Y230200D01*
X605154D01*
X604554Y229600D01*
Y228000D01*
X603954Y227400D01*
X595220D01*
X594620Y228000D01*
Y230000D01*
X594020Y230600D01*
X592820D01*
X592220Y230000D01*
Y228000D01*
X591620Y227400D01*
X588420D01*
X571720Y210700D01*
X566765D01*
X560165Y204100D01*
X486747D01*
X484947Y205900D01*
X465500D01*
X463600Y207800D01*
X440400D01*
X431500Y198900D01*
X429500D01*
G01X427496Y200303D02*
X430903D01*
X439700Y209100D01*
X465800D01*
X466700Y208200D01*
X485900D01*
X487700Y206400D01*
X559212D01*
X565812Y213000D01*
X570767D01*
X591067Y233300D01*
X640379D01*
X649404Y242325D01*
X650252D01*
X651764Y240812D01*
X652612D01*
X653462Y241662D01*
Y242510D01*
X651950Y244023D01*
Y244871D01*
X652800Y245721D01*
X653648D01*
X655310Y244058D01*
X656158D01*
X657008Y244908D01*
Y245756D01*
X655346Y247419D01*
Y248267D01*
X656196Y249117D01*
X657044D01*
X657444Y248717D01*
X658292D01*
X659142Y249567D01*
Y250415D01*
X658742Y250815D01*
Y251663D01*
X659592Y252513D01*
X660440D01*
X660840Y252113D01*
X661688D01*
X662538Y252963D01*
Y253811D01*
X662138Y254211D01*
Y255059D01*
X664079Y257000D01*
X686400D01*
X688800Y254600D01*
G01X671295Y33190D02*
Y49431D01*
X657226Y63500D01*
X648200D01*
X639834Y71866D01*
Y72714D01*
X641627Y74507D01*
Y75355D01*
X640777Y76205D01*
X639929D01*
X638136Y74412D01*
X637288D01*
X636438Y75262D01*
Y76110D01*
X638231Y77903D01*
Y78751D01*
X637381Y79601D01*
X636533D01*
X634740Y77808D01*
X633892D01*
X633042Y78658D01*
Y79506D01*
X634835Y81299D01*
Y82147D01*
X633985Y82997D01*
X633137D01*
X631344Y81204D01*
X630496D01*
X629646Y82054D01*
Y82902D01*
X631439Y84695D01*
Y85543D01*
X630589Y86393D01*
X629741D01*
X627948Y84600D01*
X627100D01*
X611696Y100004D01*
Y100852D01*
X612495Y101650D01*
Y102498D01*
X611645Y103348D01*
X610797D01*
X609998Y102550D01*
X609150D01*
X607500Y104200D01*
X438700D01*
X436500Y106400D01*
G01X685700Y30807D02*
X685625Y30882D01*
Y49669D01*
X620594Y114700D01*
X594800D01*
X594200Y115300D01*
Y116745D01*
X593600Y117345D01*
X591300D01*
X590700Y116745D01*
Y115300D01*
X590100Y114700D01*
X588900D01*
X588300Y115300D01*
Y116745D01*
X587700Y117345D01*
X586500D01*
X585900Y116745D01*
Y115300D01*
X585300Y114700D01*
X584100D01*
X583500Y115300D01*
Y116745D01*
X582900Y117345D01*
X552761D01*
X552061Y116645D01*
Y115200D01*
X551561Y114700D01*
X550161D01*
X549661Y115200D01*
Y116645D01*
X548961Y117345D01*
X547961D01*
X547261Y116645D01*
Y115200D01*
X546761Y114700D01*
X545361D01*
X544861Y115200D01*
Y116645D01*
X544161Y117345D01*
X542861D01*
X542261Y116745D01*
Y115300D01*
X541661Y114700D01*
X451800D01*
X447842Y118658D01*
X445558D01*
X444400Y117500D01*
X440900D01*
X439942Y118458D01*
G01X677295Y22807D02*
X678387Y23899D01*
Y48845D01*
X659132Y68100D01*
X655391D01*
X619916Y103575D01*
X617925D01*
X616121Y105379D01*
Y107370D01*
X614491Y109000D01*
X449444D01*
X448444Y110000D01*
X440000D01*
G01X680580Y22807D02*
X679487Y23900D01*
Y49301D01*
X659588Y69200D01*
X655847D01*
X620372Y104675D01*
X618381D01*
X617221Y105835D01*
Y107826D01*
X614947Y110100D01*
X449900D01*
X448900Y111100D01*
X440000D01*
G01X674400Y31307D02*
X673800Y31907D01*
Y50179D01*
X658179Y65800D01*
X654437D01*
X653091Y67146D01*
Y67147D01*
X651793Y68445D01*
X650945D01*
X649152Y66652D01*
X648304D01*
X647454Y67502D01*
Y68350D01*
X649247Y70143D01*
Y70991D01*
X648397Y71841D01*
X647549D01*
X645756Y70048D01*
X644908D01*
X644058Y70898D01*
Y71746D01*
X645851Y73539D01*
Y74387D01*
X629930Y90308D01*
X629082D01*
X627561Y88787D01*
X626713D01*
X625863Y89637D01*
Y90485D01*
X627384Y92006D01*
Y92854D01*
X626534Y93704D01*
X625686D01*
X624665Y92683D01*
X623817D01*
X622967Y93533D01*
Y94381D01*
X624019Y95433D01*
Y96219D01*
X622512Y97726D01*
X621726D01*
X620074Y96074D01*
X619226D01*
X617973Y97327D01*
Y100274D01*
X611747Y106500D01*
X447400D01*
X446100Y107800D01*
X438758D01*
G01X681900Y30907D02*
X683012Y32019D01*
Y49029D01*
X657281Y74760D01*
X654040D01*
X653190Y75610D01*
Y76457D01*
X653963Y77230D01*
Y78078D01*
X653113Y78928D01*
X652265D01*
X651592Y78255D01*
X650745D01*
X649894Y79106D01*
Y79953D01*
X650567Y80626D01*
Y81474D01*
X649717Y82324D01*
X648869D01*
X648246Y81702D01*
X646598D01*
X615900Y112400D01*
X581900D01*
X581300Y113000D01*
Y114400D01*
X580700Y115000D01*
X579300D01*
X578700Y114400D01*
Y113000D01*
X578100Y112400D01*
X576556D01*
X575956Y113000D01*
Y114545D01*
X575456Y115045D01*
X574056D01*
X573556Y114545D01*
Y113000D01*
X572956Y112400D01*
X571756D01*
X571156Y113000D01*
Y114545D01*
X570656Y115045D01*
X569256D01*
X568756Y114545D01*
Y113000D01*
X568156Y112400D01*
X566956D01*
X566356Y113000D01*
Y114545D01*
X565856Y115045D01*
X564456D01*
X563956Y114545D01*
Y113000D01*
X563356Y112400D01*
X562156D01*
X561556Y113000D01*
Y114545D01*
X561056Y115045D01*
X559656D01*
X559156Y114545D01*
Y113000D01*
X558556Y112400D01*
X451000D01*
X448800Y114600D01*
X437513D01*
X437013Y115100D01*
G01X721500Y255000D02*
X721600Y254900D01*
Y254800D01*
X723100Y253300D01*
Y248340D01*
X722100Y247340D01*
Y242091D01*
X712400Y232391D01*
Y226779D01*
X694744Y209123D01*
X681823D01*
X651600Y178900D01*
X614828Y168900D01*
X606300Y166900D01*
X545546D01*
X544946Y167500D01*
Y167993D01*
X544346Y168593D01*
X543146D01*
X542546Y167993D01*
Y167500D01*
X541946Y166900D01*
X540746D01*
X540146Y167500D01*
Y167993D01*
X539546Y168593D01*
X538346D01*
X537746Y167993D01*
Y167500D01*
X537146Y166900D01*
X535946D01*
X535346Y167500D01*
Y167993D01*
X534746Y168593D01*
X533546D01*
X532946Y167993D01*
Y167500D01*
X532346Y166900D01*
X531146D01*
X530546Y167500D01*
Y167993D01*
X529946Y168593D01*
X528746D01*
X528146Y167993D01*
Y167500D01*
X527546Y166900D01*
X526346D01*
X525746Y167500D01*
Y167993D01*
X525146Y168593D01*
X523946D01*
X523346Y167993D01*
Y167500D01*
X522746Y166900D01*
X521546D01*
X520946Y167500D01*
Y167993D01*
X520346Y168593D01*
X519146D01*
X518546Y167993D01*
Y167500D01*
X517946Y166900D01*
X516746D01*
X516146Y167500D01*
Y167993D01*
X515546Y168593D01*
X514346D01*
X513746Y167993D01*
Y167500D01*
X513146Y166900D01*
X511946D01*
X511346Y167500D01*
Y167993D01*
X510746Y168593D01*
X509546D01*
X508946Y167993D01*
Y167500D01*
X508346Y166900D01*
X507146D01*
X506546Y167500D01*
Y167993D01*
X505946Y168593D01*
X504746D01*
X504146Y167993D01*
Y167500D01*
X503546Y166900D01*
X502346D01*
X501746Y167500D01*
Y167993D01*
X501146Y168593D01*
X499946D01*
X499346Y167993D01*
Y167500D01*
X498746Y166900D01*
X497546D01*
X496946Y167500D01*
Y167993D01*
X496346Y168593D01*
X495146D01*
X494546Y167993D01*
Y167500D01*
X493946Y166900D01*
X492746D01*
X492146Y167500D01*
Y167993D01*
X491546Y168593D01*
X490346D01*
X489746Y167993D01*
Y167500D01*
X489146Y166900D01*
X487946D01*
X487346Y167500D01*
Y167993D01*
X486746Y168593D01*
X485546D01*
X484946Y167993D01*
Y167500D01*
X484346Y166900D01*
X468300D01*
X465200Y163800D01*
X442200D01*
X439900Y166100D01*
X439000D01*
G01X440500Y158000D02*
X447300Y160000D01*
X608381D01*
X654056Y171450D01*
X698139Y202759D01*
X719300Y223920D01*
X727360Y236853D01*
X728700Y245300D01*
Y253500D01*
X725300Y272800D01*
G01X724374Y254515D02*
Y254174D01*
X724200Y254000D01*
Y240938D01*
X714700Y231438D01*
Y225826D01*
X695697Y206823D01*
X682776D01*
X680813Y204860D01*
Y204012D01*
X681988Y202836D01*
Y201988D01*
X681138Y201138D01*
X680290D01*
X679115Y202314D01*
X678267D01*
X677417Y201464D01*
Y200616D01*
X678492Y199540D01*
Y198692D01*
X677642Y197842D01*
X676794D01*
X675719Y198918D01*
X674871D01*
X674021Y198068D01*
Y197220D01*
X675546Y195694D01*
Y194846D01*
X674696Y193996D01*
X673848D01*
X672323Y195522D01*
X671475D01*
X670625Y194672D01*
Y193824D01*
X671500Y192949D01*
Y192101D01*
X670650Y191251D01*
X669802D01*
X668927Y192126D01*
X668079D01*
X667229Y191276D01*
Y190428D01*
X668505Y189153D01*
Y188305D01*
X667654Y187454D01*
X666806D01*
X665531Y188730D01*
X664683D01*
X663833Y187880D01*
Y187032D01*
X664708Y186157D01*
Y185309D01*
X663858Y184459D01*
X663010D01*
X662135Y185334D01*
X661287D01*
X652794Y176841D01*
X617118Y167139D01*
X615435Y166681D01*
X607215Y164600D01*
X468600D01*
X466600Y162600D01*
X439000D01*
X436600Y165000D01*
G01X436800Y161700D02*
X437200Y161300D01*
X467800D01*
X468800Y162300D01*
X607500D01*
X653103Y173750D01*
X685455Y196611D01*
X685599Y197447D01*
X684882Y198462D01*
X685026Y199297D01*
X686008Y199991D01*
X686843Y199847D01*
X687560Y198832D01*
X688395Y198689D01*
X689377Y199383D01*
X689521Y200219D01*
X688804Y201234D01*
X688948Y202069D01*
X689930Y202763D01*
X690765Y202619D01*
X691482Y201604D01*
X692317Y201461D01*
X696650Y204523D01*
X717000Y224873D01*
X725600Y238719D01*
X727600Y248309D01*
Y253415D01*
X723500Y262800D01*
Y266200D01*
X722400Y267300D01*
Y270800D01*
G01X711400Y255072D02*
Y254900D01*
X710430Y253930D01*
Y251016D01*
X711478Y249968D01*
Y245878D01*
X702100Y236500D01*
Y231147D01*
X690376Y219423D01*
X688076D01*
X687476Y220023D01*
Y222900D01*
X686876Y223500D01*
X685676D01*
X685076Y222900D01*
Y220023D01*
X684476Y219423D01*
X683276D01*
X682676Y220023D01*
Y222900D01*
X682076Y223500D01*
X680876D01*
X680276Y222900D01*
Y220023D01*
X679676Y219423D01*
X678476D01*
X677876Y220023D01*
Y222900D01*
X677276Y223500D01*
X676076D01*
X675476Y222900D01*
Y220023D01*
X674876Y219423D01*
X670176D01*
X647103Y196350D01*
X622868D01*
X622268Y196950D01*
Y197700D01*
X621668Y198300D01*
X620468D01*
X619868Y197700D01*
Y196950D01*
X619268Y196350D01*
X618150D01*
X617350Y195550D01*
X614700D01*
X614100Y194950D01*
Y192200D01*
X613500Y191600D01*
X612300D01*
X611700Y192200D01*
Y198500D01*
X611100Y199100D01*
X609920D01*
X607047Y196227D01*
Y195379D01*
X608939Y193487D01*
Y192639D01*
X608089Y191789D01*
X607241D01*
X605349Y193681D01*
X604501D01*
X603651Y192831D01*
Y191983D01*
X605543Y190091D01*
Y189243D01*
X604693Y188393D01*
X603845D01*
X601953Y190285D01*
X601105D01*
X598822Y188002D01*
Y186125D01*
X595275Y182578D01*
Y182529D01*
X591946Y179200D01*
X590700D01*
X589500Y180400D01*
X588300D01*
X587100Y179200D01*
X480385D01*
X479085Y177900D01*
X476800D01*
X474750Y179950D01*
X465250D01*
X462200Y176900D01*
X451100D01*
X450100Y177900D01*
X446200D01*
G01X709400Y272600D02*
X708900Y272100D01*
Y257600D01*
X709500Y257000D01*
X713400D01*
X714000Y256400D01*
Y245800D01*
X704400Y236200D01*
Y230094D01*
X691429Y217123D01*
X671129D01*
X648056Y194050D01*
X619103D01*
X616100Y191047D01*
Y182800D01*
X615500Y182200D01*
X614200D01*
X613600Y182800D01*
Y188700D01*
X613000Y189300D01*
X611745D01*
X611145Y188700D01*
Y182790D01*
X610545Y182190D01*
X609300D01*
X608700Y182790D01*
Y184800D01*
X608100Y185400D01*
X606900D01*
X606300Y184800D01*
Y182790D01*
X605700Y182190D01*
X604710D01*
X602425Y184475D01*
X600425D01*
X596525Y180575D01*
Y178237D01*
X595188Y176900D01*
X481338D01*
X479338Y174900D01*
X466000D01*
X463200Y172100D01*
X460200D01*
X459300Y173000D01*
X450200D01*
X449200Y172000D01*
X447200D01*
X446200Y173000D01*
X444800D01*
G01X442500Y171019D02*
X443281D01*
X445000Y169300D01*
X463900D01*
X467200Y172600D01*
X480291D01*
X482291Y174600D01*
X596141D01*
X601431Y179890D01*
X617490D01*
X618400Y180800D01*
Y190094D01*
X620056Y191750D01*
X649009D01*
X655124Y197865D01*
X655972D01*
X656544Y197294D01*
X657392D01*
X658242Y198144D01*
Y198992D01*
X657670Y199564D01*
Y200411D01*
X658520Y201261D01*
X659368D01*
X659940Y200690D01*
X660788D01*
X661638Y201540D01*
Y202388D01*
X661066Y202960D01*
Y203807D01*
X661916Y204657D01*
X662764D01*
X663336Y204086D01*
X664184D01*
X665034Y204936D01*
Y205784D01*
X664462Y206356D01*
Y207203D01*
X667906Y210647D01*
X668754D01*
X670577Y208825D01*
X671425D01*
X672275Y209675D01*
Y210523D01*
X670452Y212345D01*
Y213193D01*
X672082Y214823D01*
X692382D01*
X706700Y229141D01*
Y235200D01*
X715900Y244400D01*
Y250600D01*
X715100Y251400D01*
X715037D01*
Y255702D01*
X715637Y256302D01*
X716700D01*
X717300Y256902D01*
Y258102D01*
X716700Y258702D01*
X715637D01*
X715037Y259302D01*
Y261400D01*
X714437Y262000D01*
X711300D01*
X710700Y262600D01*
Y263900D01*
X711237Y264437D01*
X714300D01*
X714900Y265037D01*
Y266237D01*
X714300Y266837D01*
X712077D01*
X711477Y267437D01*
Y269777D01*
X712200Y270500D01*
G01X439800Y185900D02*
X447900Y194000D01*
Y197700D01*
X449100Y198900D01*
X462600D01*
X466000Y195500D01*
X480779D01*
X482479Y193800D01*
X564433D01*
X571033Y200400D01*
X586100D01*
X594763Y209063D01*
Y209911D01*
X593518Y211156D01*
Y212004D01*
X594368Y212854D01*
X595216D01*
X596461Y211609D01*
X597309D01*
X598159Y212459D01*
Y213307D01*
X596914Y214552D01*
Y215400D01*
X597764Y216250D01*
X598612D01*
X599857Y215005D01*
X600705D01*
X602800Y217100D01*
X605100D01*
X605700Y216500D01*
Y215700D01*
X606300Y215100D01*
X607500D01*
X608100Y215700D01*
Y216500D01*
X608700Y217100D01*
X642000D01*
X652334Y227434D01*
X660475D01*
X672541Y239500D01*
X690178D01*
X701450Y250772D01*
Y252914D01*
X699900Y254464D01*
Y259300D01*
X701977Y261377D01*
Y270100D01*
X701300Y270777D01*
G01X701649Y255049D02*
X702528Y254170D01*
Y249228D01*
X689950Y236650D01*
X672944D01*
X661428Y225134D01*
X659187D01*
X658587Y224534D01*
Y222300D01*
X657987Y221700D01*
X656787D01*
X656187Y222300D01*
Y224534D01*
X655587Y225134D01*
X653287D01*
X650265Y222112D01*
Y221264D01*
X653486Y218043D01*
Y217195D01*
X652636Y216345D01*
X651788D01*
X648567Y219566D01*
X647719D01*
X642953Y214800D01*
X610453D01*
X608453Y212800D01*
X601753D01*
X594782Y205829D01*
Y204981D01*
X595558Y204205D01*
Y203358D01*
X594708Y202508D01*
X593860D01*
X593084Y203283D01*
X592236D01*
X591386Y202433D01*
Y201585D01*
X592018Y200953D01*
Y200105D01*
X591168Y199255D01*
X590320D01*
X589688Y199887D01*
X588840D01*
X587053Y198100D01*
X571986D01*
X565386Y191500D01*
X481526D01*
X479826Y193200D01*
X465500D01*
X463600Y195100D01*
X451600D01*
X448500Y192000D01*
G01X699477Y262489D02*
X698085Y261097D01*
Y250032D01*
X689853Y241800D01*
X671588D01*
X659522Y229734D01*
X651381D01*
X641047Y219400D01*
X597456D01*
X586800Y208744D01*
Y205044D01*
X584456Y202700D01*
X570080D01*
X563480Y196100D01*
X483432D01*
X481632Y197900D01*
X465344D01*
X460244Y203000D01*
X447356D01*
X441550Y197194D01*
Y193443D01*
X441050Y192943D01*
Y191208D01*
X437357Y187515D01*
G01X696192Y262489D02*
X696985Y261696D01*
Y250488D01*
X689397Y242900D01*
X671132D01*
X659066Y230834D01*
X650925D01*
X640591Y220500D01*
X597000D01*
X585700Y209200D01*
Y205500D01*
X584000Y203800D01*
X569624D01*
X563024Y197200D01*
X483888D01*
X482088Y199000D01*
X465800D01*
X460700Y204100D01*
X446900D01*
X440450Y197650D01*
Y193899D01*
X439950Y193399D01*
Y191664D01*
X436579Y188293D01*
G01X692537Y272989D02*
Y271073D01*
X693700Y269910D01*
Y260200D01*
X695550Y258350D01*
Y250950D01*
X689900Y245300D01*
X670279D01*
X658539Y233560D01*
X650398D01*
X639638Y222800D01*
X590326D01*
X573626Y206100D01*
X568671D01*
X562071Y199500D01*
X484841D01*
X483041Y201300D01*
X465700D01*
X461600Y205400D01*
X444200D01*
X436600Y197800D01*
G01X433835Y199065D02*
X435500D01*
X443035Y206600D01*
X462600D01*
X465600Y203600D01*
X483994D01*
X485794Y201800D01*
X561118D01*
X567718Y208400D01*
X572673D01*
X589373Y225100D01*
X638685D01*
X649472Y235887D01*
X657613D01*
X669426Y247700D01*
X689480D01*
X692195Y250415D01*
Y252975D01*
X692210Y252990D01*
Y253014D01*
X694200Y255004D01*
Y257160D01*
X690237Y261123D01*
Y270263D01*
X689700Y270800D01*
G01X707800Y255000D02*
X707900D01*
X709240Y253660D01*
Y249850D01*
X708964Y249574D01*
Y246764D01*
X699800Y237600D01*
Y232100D01*
X695600Y227900D01*
X692800D01*
X692200Y227300D01*
Y224500D01*
X691400Y223700D01*
X689929D01*
X689100Y224529D01*
Y228150D01*
X688500Y228750D01*
X686400D01*
X685800Y228150D01*
Y226400D01*
X685200Y225800D01*
X684000D01*
X683400Y226400D01*
Y228150D01*
X682800Y228750D01*
X681600D01*
X681000Y228150D01*
Y226400D01*
X680400Y225800D01*
X679200D01*
X678600Y226400D01*
Y228150D01*
X678000Y228750D01*
X676800D01*
X676200Y228150D01*
Y226400D01*
X675600Y225800D01*
X673300D01*
X672700Y225200D01*
Y224300D01*
X673176Y223824D01*
Y222700D01*
X672199Y221723D01*
X669223D01*
X646150Y198650D01*
X644600D01*
X643050Y200200D01*
X641700D01*
X640150Y198650D01*
X638838D01*
X637288Y200200D01*
X624921D01*
X623721Y201400D01*
X621300D01*
X620600Y200700D01*
X618900D01*
X618200Y201400D01*
X616200D01*
X615400Y200600D01*
X613200D01*
X612400Y201400D01*
X608967D01*
X596522Y188955D01*
Y187078D01*
X595369Y185925D01*
X587425D01*
X586675Y185175D01*
Y182554D01*
X585621Y181500D01*
X524027D01*
X523427Y182100D01*
Y183000D01*
X522827Y183600D01*
X521627D01*
X521027Y183000D01*
Y182100D01*
X520427Y181500D01*
X479633D01*
X477533Y183600D01*
X464300D01*
X463100Y184800D01*
X461200D01*
X460472Y184072D01*
Y180100D01*
X459872Y179500D01*
X458672D01*
X458072Y180100D01*
Y184400D01*
X457472Y185000D01*
X456272D01*
X455672Y184400D01*
Y180200D01*
X455072Y179600D01*
X453872D01*
X453272Y180200D01*
Y183000D01*
X452672Y183600D01*
X450300D01*
G01X704178Y252189D02*
Y248278D01*
X690250Y234350D01*
X673897D01*
X652047Y212500D01*
X650000D01*
X649400Y213100D01*
Y215400D01*
X648800Y216000D01*
X647600D01*
X647000Y215400D01*
Y213100D01*
X646400Y212500D01*
X611406D01*
X609406Y210500D01*
X606752D01*
X605031Y208779D01*
Y207931D01*
X605907Y207055D01*
Y206260D01*
X605004Y205357D01*
X604209D01*
X603766Y205800D01*
X599600D01*
X598469Y204669D01*
Y203821D01*
X600544Y201746D01*
Y200898D01*
X599694Y200048D01*
X598846D01*
X597997Y200897D01*
X597149D01*
X596299Y200047D01*
Y199199D01*
X597148Y198350D01*
Y197502D01*
X596298Y196652D01*
X595450D01*
X594601Y197501D01*
X593753D01*
X592052Y195800D01*
X572939D01*
X566339Y189200D01*
X493961D01*
X493361Y188600D01*
Y187814D01*
X492761Y187214D01*
X491561D01*
X490961Y187814D01*
Y188600D01*
X490361Y189200D01*
X489161D01*
X488561Y188600D01*
Y187800D01*
X487961Y187200D01*
X486761D01*
X486161Y187800D01*
Y188600D01*
X485561Y189200D01*
X484361D01*
X483761Y188600D01*
Y187814D01*
X483161Y187214D01*
X482086D01*
X478200Y191100D01*
X476143D01*
X475543Y190500D01*
Y189200D01*
X474943Y188600D01*
X473743D01*
X473143Y189200D01*
Y190500D01*
X472543Y191100D01*
X457630D01*
X457030Y190500D01*
Y189800D01*
X456430Y189200D01*
X455230D01*
X454630Y189800D01*
Y190500D01*
X454030Y191100D01*
X450900D01*
X450600Y190800D01*
G01X704277Y272989D02*
X704100Y272812D01*
Y266450D01*
X704877Y265673D01*
X706300D01*
X706900Y265073D01*
Y263873D01*
X706300Y263273D01*
X704877D01*
X704277Y262673D01*
Y261223D01*
X705000Y260500D01*
X706200D01*
X706800Y259900D01*
Y257440D01*
X705840Y256480D01*
Y246640D01*
X696600Y237400D01*
Y235100D01*
X695000Y233500D01*
X692700D01*
X691250Y232050D01*
X674850D01*
X653000Y210200D01*
X613100D01*
X596400Y193500D01*
X580888D01*
X580288Y192900D01*
Y192300D01*
X579688Y191700D01*
X578488D01*
X577888Y192300D01*
Y192900D01*
X577288Y193500D01*
X573892D01*
X567292Y186900D01*
X495700D01*
X493600Y184800D01*
X481000D01*
X478500Y187300D01*
X452681D01*
G01X464909Y166865D02*
X468344Y170300D01*
X481244D01*
X483244Y172300D01*
X597094D01*
X601894Y177100D01*
X603739D01*
X604229Y177590D01*
X606029D01*
X606519Y177100D01*
X608319D01*
X608809Y177590D01*
X610609D01*
X611099Y177100D01*
X619844D01*
X620900Y178156D01*
Y188156D01*
X622144Y189400D01*
X625056D01*
X626300Y188156D01*
Y178000D01*
X626900Y177400D01*
X628900D01*
X629500Y178000D01*
Y188206D01*
X630744Y189450D01*
X656650D01*
X679723Y212523D01*
X693335D01*
X709000Y228188D01*
Y233800D01*
X710273Y235073D01*
Y235766D01*
X711546Y237039D01*
X712239D01*
X713511Y238311D01*
Y239004D01*
X714784Y240277D01*
X715477D01*
X718600Y243400D01*
Y248844D01*
X718110Y249334D01*
Y251134D01*
X718600Y251624D01*
Y253424D01*
X718110Y253914D01*
Y255714D01*
X718600Y256204D01*
Y261341D01*
X717452Y262489D01*
G01X720737D02*
X719700Y261452D01*
Y242944D01*
X710100Y233344D01*
Y227732D01*
X693791Y211423D01*
X680179D01*
X657106Y188350D01*
X631200D01*
X630600Y187750D01*
Y177544D01*
X629356Y176300D01*
X626444D01*
X625200Y177544D01*
Y187700D01*
X624600Y188300D01*
X622600D01*
X622000Y187700D01*
Y177700D01*
X620300Y176000D01*
X602350D01*
X597550Y171200D01*
X483700D01*
X481700Y169200D01*
X468800D01*
X465565Y165965D01*
G54D12*
X199600Y160100D03*
X699000Y162255D03*
X784000Y31000D03*
X782000Y137000D03*
X811000Y130000D03*
Y134000D03*
X809000Y149200D03*
X811000Y138000D03*
X811200Y141600D03*
X809500Y156900D03*
X809600Y160500D03*
X809700Y164300D03*
G54D22*
G01X16900Y269000D02*
X18749Y267151D01*
Y223899D01*
X11000Y216150D01*
Y175000D01*
X18850Y167150D01*
Y144533D01*
X29233Y134150D01*
X78550D01*
X92100Y120600D01*
X124500D01*
X126050Y119050D01*
X141850D01*
X146950Y124150D01*
X151437D01*
X153587Y122000D01*
X157776D01*
X166000Y113776D01*
Y101383D01*
X177433Y89950D01*
X195950D01*
X197750Y91750D01*
X216211D01*
X217615Y90346D01*
X235788D01*
X235892Y90450D01*
X238792D01*
X239192Y90050D01*
X248092D01*
X251942Y86200D01*
X296700D01*
X299800Y89300D01*
Y93834D01*
X301166Y95200D01*
X303376D01*
G01X633319Y155008D02*
X637177Y151150D01*
X643967D01*
X651350Y143767D01*
Y141988D01*
X666838Y126500D01*
X719000D01*
X722000Y123500D01*
X730000D01*
X731050Y124550D01*
X750567D01*
X755617Y119500D01*
X775500D01*
X786000Y130000D01*
X811000D01*
G01X618500Y159000D02*
X619383D01*
X623233Y155150D01*
X630597D01*
X633107Y157660D01*
X650840D01*
X653667Y154833D01*
X679239D01*
X699022Y135050D01*
X714295D01*
X729155Y149910D01*
X808290D01*
X809000Y149200D01*
G01X625500Y159000D02*
X627350Y157150D01*
X629767D01*
X632277Y159660D01*
X677242D01*
X699852Y137050D01*
X713465D01*
X728415Y152000D01*
X801100D01*
X809600Y160500D01*
G01X809500Y156900D02*
X803600Y151000D01*
X728830D01*
X713880Y136050D01*
X699437D01*
X676827Y158660D01*
X632692D01*
X630182Y156150D01*
X624850D01*
X622000Y159000D01*
G01X809700Y164300D02*
X798400Y153000D01*
X728000D01*
X713050Y138050D01*
X700267D01*
X677657Y160660D01*
X630660D01*
X629000Y159000D01*
G01X636719Y154972D02*
X639541Y152150D01*
X644382D01*
X652350Y144182D01*
Y142403D01*
X667253Y127500D01*
X719415D01*
X722415Y124500D01*
X729585D01*
X730635Y125550D01*
X750982D01*
X756032Y120500D01*
X775085D01*
X785585Y131000D01*
X808000D01*
X811000Y134000D01*
G01X643500Y155000D02*
X644362D01*
X654350Y145012D01*
Y143233D01*
X668083Y129500D01*
X720245D01*
X723245Y126500D01*
X728755D01*
X729805Y127550D01*
X751812D01*
X756862Y122500D01*
X774255D01*
X784755Y133000D01*
X802600D01*
X811200Y141600D01*
G01X640110Y155272D02*
X642232Y153150D01*
X644797D01*
X653350Y144597D01*
Y142818D01*
X667668Y128500D01*
X719830D01*
X722830Y125500D01*
X729170D01*
X730220Y126550D01*
X751397D01*
X756447Y121500D01*
X774670D01*
X785170Y132000D01*
X805000D01*
X811000Y138000D01*
G54D13*
X276811Y263386D03*
X296811D03*
X457913Y45276D03*
X477913D03*
G54D23*
G01X805500Y128000D02*
X807500Y126000D01*
Y111500D01*
X805500Y109500D01*
X780000D01*
X771900Y117600D01*
X754900D01*
X752000Y120500D01*
X734200D01*
X732000Y122700D01*
G54D14*
X309194Y117700D03*
X306994Y117725D03*
X309700Y122796D03*
X307500Y122700D03*
X305050Y151150D03*
X329300Y87300D03*
X331200Y88600D03*
X330100Y100200D03*
Y98000D03*
X329415Y119923D03*
X333601Y120500D03*
X333534Y118040D03*
X329308Y122386D03*
X372700Y119663D03*
X370100Y119563D03*
X368026Y137118D03*
X364700Y134000D03*
X367992Y133982D03*
X361700Y143300D03*
X364886Y140268D03*
X368026D03*
Y143418D03*
X364621Y143328D03*
X361600Y159250D03*
X381600Y119900D03*
X381900Y113000D03*
X382596Y108600D03*
X385600Y116500D03*
X385200Y113137D03*
X385721Y119528D03*
X385479Y125569D03*
X381500Y123200D03*
X381600Y126427D03*
X385523Y122532D03*
X384740Y180080D03*
X381720Y180220D03*
X381800Y183300D03*
X380540Y177370D03*
X381460Y195610D03*
X384390Y196470D03*
X381140Y187960D03*
X381280Y191550D03*
X384708Y188910D03*
X384600Y186100D03*
X385947Y226500D03*
X385900Y218400D03*
X390700Y89300D03*
X403726Y83826D03*
X403700Y90200D03*
X397300Y89168D03*
X400400Y92200D03*
Y98500D03*
X390750Y96500D03*
X394100Y91400D03*
Y99000D03*
X397100Y96600D03*
X393000Y152663D03*
X402900Y149663D03*
X403080Y146931D03*
X399198Y146468D03*
X396192Y146444D03*
X392998Y149718D03*
X399198Y149618D03*
X396182Y149674D03*
X396200Y152763D03*
X396300Y162100D03*
X399300Y152863D03*
Y155963D03*
X393028Y162059D03*
X393198Y158940D03*
X403078Y152922D03*
X402373Y155952D03*
X399298Y162090D03*
X402505Y159133D03*
X396148Y158940D03*
X399298D03*
X392100Y213700D03*
X389100Y224000D03*
X399700Y225000D03*
Y216400D03*
X395600Y224400D03*
X395700Y217000D03*
X391950Y220800D03*
X389150Y230300D03*
X416904Y119591D03*
X415000Y131400D03*
X408956Y130064D03*
X418500Y128200D03*
X415100Y127900D03*
X416851Y122600D03*
X406000Y150200D03*
X407500Y152100D03*
X410400Y152000D03*
X418439Y167118D03*
X407500Y157600D03*
X412900Y157800D03*
X407400Y154863D03*
X406100Y159500D03*
X415100Y158100D03*
X410272Y154794D03*
X416400Y155000D03*
X408600Y159600D03*
X411600D03*
X404558Y154835D03*
X414960Y178130D03*
X414950Y181460D03*
X411260Y178090D03*
X411553Y181222D03*
X416400Y170300D03*
X413265Y170423D03*
X430100Y131500D03*
X431700Y128300D03*
X423500Y128200D03*
X427000Y128050D03*
X423900Y131500D03*
X420942Y131324D03*
X434700Y131800D03*
X432542Y136898D03*
X428238Y167709D03*
X425500Y154737D03*
X428400D03*
X430360Y181350D03*
X430340Y177620D03*
X423642Y181374D03*
X426970Y178310D03*
X425400Y170240D03*
X428500Y173120D03*
X422337Y170575D03*
X425427Y173113D03*
X419453Y173187D03*
X420922Y178117D03*
X423842Y178274D03*
X428431Y170264D03*
X443443Y144757D03*
X437398Y146257D03*
X435004Y142110D03*
X443400Y148900D03*
X437472Y152501D03*
X439600Y153800D03*
X530015Y255000D03*
X531775Y252231D03*
X541005Y254800D03*
X530900Y273000D03*
X534100Y270700D03*
X541500Y270900D03*
X535562Y262489D03*
X538847D03*
X550000Y12507D03*
X552800Y14807D03*
X557745Y22907D03*
X554460D03*
X553079Y30712D03*
X549500Y31607D03*
X544800Y255100D03*
X544292Y273128D03*
X568555Y12407D03*
X561200Y12507D03*
X571600Y14207D03*
X564400Y14307D03*
X570852Y33204D03*
X569800Y29807D03*
X565091Y30815D03*
X561456Y30902D03*
X568327Y253348D03*
X571867Y254685D03*
X567800Y270500D03*
X570200Y273100D03*
X582655Y12407D03*
X579800Y14807D03*
X577824Y22907D03*
X574539D03*
X585179Y30867D03*
X581450Y30707D03*
X579205Y254850D03*
X582200Y252206D03*
X580200Y273000D03*
X582600Y270300D03*
X573357Y262489D03*
X576642D03*
X594500Y4007D03*
X603187Y252056D03*
X589500Y257100D03*
X589900Y268133D03*
X602450Y272900D03*
X598418Y262699D03*
X590322Y262361D03*
X594559Y262559D03*
X595386Y272932D03*
X614700Y14107D03*
X615951Y22356D03*
X615044Y33190D03*
X618877Y30790D03*
X608700Y257300D03*
X611845Y253723D03*
X611593Y261885D03*
X606200Y267800D03*
X615430Y262213D03*
X612393Y273026D03*
X619180Y262689D03*
X633500Y12406D03*
X624000D03*
X634757Y22707D03*
X623480Y22564D03*
X631007Y22707D03*
X619700Y22307D03*
X627257Y22407D03*
X624100Y33190D03*
X633449D03*
X629937Y272990D03*
X630457Y262832D03*
X626680Y262989D03*
X634280Y262832D03*
X620437Y272990D03*
X622930Y262689D03*
X641745Y12367D03*
X645200Y27707D03*
X646800Y17607D03*
X642257Y23307D03*
X638507Y23183D03*
X650200Y33307D03*
X641900Y31507D03*
X635197Y254602D03*
X638893Y252206D03*
X637987Y262842D03*
X639500Y268800D03*
X657897Y12504D03*
X651316Y12360D03*
X655592Y22723D03*
X659400Y23207D03*
X657900Y33190D03*
X671290Y12457D03*
X674320Y14219D03*
X680580Y22807D03*
X677295D03*
X674400Y31307D03*
X671295Y33190D03*
X684760Y12256D03*
X687602Y12439D03*
X694200Y13507D03*
X682013Y14848D03*
X694205Y20302D03*
X685700Y30807D03*
X681900Y30907D03*
X688800Y254600D03*
X692250Y255700D03*
X689700Y270800D03*
X692537Y272989D03*
X696192Y262489D03*
X699503Y12482D03*
X706360Y12397D03*
X705604Y16949D03*
X710813Y28796D03*
X699104Y20495D03*
X707157Y33333D03*
X700940Y33340D03*
X701649Y255049D03*
X704178Y252189D03*
X707800Y255000D03*
X711400Y255072D03*
X701300Y270777D03*
X704277Y272989D03*
X709400Y272600D03*
X699477Y262489D03*
X714000Y12407D03*
X719110Y12347D03*
X725530Y12507D03*
X714100Y20607D03*
X719220Y20553D03*
X721074Y30514D03*
X718350Y33107D03*
X712450Y33340D03*
X725653Y32654D03*
X721500Y255000D03*
X724374Y254515D03*
X712200Y270500D03*
X722400Y270800D03*
X725300Y272800D03*
X717452Y262489D03*
X720737D03*
X737300Y12307D03*
X732110Y12267D03*
X728500Y15507D03*
X742100Y28107D03*
X732000Y20307D03*
X736748D03*
X728500Y27907D03*
X733474Y33340D03*
X738487Y33094D03*
X730300Y257900D03*
X734937Y253100D03*
X739750Y252800D03*
X729860Y269810D03*
X734200Y265100D03*
X739111Y264962D03*
X727800Y272800D03*
X734510Y273110D03*
X745100Y12256D03*
X744800Y33007D03*
X744100Y254800D03*
X749000Y252200D03*
G54D24*
G01X57400Y210700D02*
X58712Y212012D01*
X104288D01*
X116975Y199325D01*
X130877D01*
X135227Y203675D01*
X153736D01*
X155897Y201514D01*
X198346D01*
X199285Y200575D01*
X205686D01*
X218961Y187300D01*
X243700D01*
X262500Y168500D01*
X273578D01*
X276178Y165900D01*
X284900D01*
X293200Y157600D01*
X297600D01*
X304050Y151150D01*
X305050D01*
G01X718200Y147000D02*
X721000Y149800D01*
Y177741D01*
X748659Y205400D01*
X755300D01*
X767087Y217187D01*
Y271762D01*
X767088Y271763D01*
Y273171D01*
X753183Y287076D01*
X356861D01*
X345860Y276075D01*
X334808D01*
X334807Y276076D01*
X331989D01*
X330438Y274525D01*
X295275D01*
X291102Y278698D01*
X235593D01*
X229820Y272925D01*
X184585D01*
X175035Y282475D01*
X65154D01*
X52025Y269346D01*
Y247999D01*
X56724Y243300D01*
G01X56800Y249613D02*
Y247850D01*
X56450Y247500D01*
X55075D01*
X53725Y248850D01*
Y268641D01*
X65859Y280775D01*
X174330D01*
X183880Y271225D01*
X230525D01*
X236298Y276998D01*
X290397D01*
X294570Y272825D01*
X331143D01*
X332694Y274376D01*
X334102D01*
X334103Y274375D01*
X346565D01*
X357566Y285376D01*
X752478D01*
X765387Y272467D01*
Y218087D01*
X754500Y207200D01*
X748054D01*
X719300Y178446D01*
Y175846D01*
X718950Y175496D01*
X716850D01*
X716500Y175146D01*
Y173746D01*
X716850Y173396D01*
X718950D01*
X719300Y173046D01*
Y171646D01*
X718950Y171296D01*
X717050D01*
X716700Y170946D01*
Y169546D01*
X717050Y169196D01*
X718950D01*
X719300Y168846D01*
Y167446D01*
X718950Y167096D01*
X717050D01*
X716700Y166746D01*
Y165346D01*
X717050Y164996D01*
X718950D01*
X719300Y164646D01*
Y163246D01*
X718950Y162896D01*
X717200D01*
X716800Y162496D01*
Y161196D01*
X717200Y160796D01*
X718950D01*
X719300Y160446D01*
Y155928D01*
X718825Y155453D01*
G01X58102Y246471D02*
X59400Y247769D01*
Y251300D01*
X58900Y251800D01*
X55925D01*
X55425Y252300D01*
Y267936D01*
X66564Y279075D01*
X173625D01*
X183175Y269525D01*
X231230D01*
X237002Y275297D01*
X289693D01*
X293865Y271125D01*
X331848D01*
X333398Y272675D01*
X347270D01*
X358271Y283676D01*
X751773D01*
X763687Y271762D01*
Y218887D01*
X753700Y208900D01*
X747349D01*
X714475Y176026D01*
Y172849D01*
X715000Y172324D01*
Y170749D01*
X714475Y170224D01*
Y168649D01*
X715000Y168124D01*
Y166549D01*
X714475Y166024D01*
Y164449D01*
X715000Y163924D01*
Y162349D01*
X714475Y161824D01*
Y159691D01*
X714825Y159341D01*
X716300D01*
X716900Y158741D01*
Y157841D01*
X716300Y157241D01*
X714825D01*
X714475Y156891D01*
Y155491D01*
X714825Y155141D01*
X716600D01*
X717000Y154741D01*
Y153441D01*
X716600Y153041D01*
X714350D01*
X714000Y152691D01*
Y149450D01*
X714350Y149100D01*
X716900D01*
X718200Y150400D01*
G01X131762Y141796D02*
X134381Y139177D01*
Y137289D01*
X135420Y136250D01*
X164661D01*
X173575Y127336D01*
Y125625D01*
X191425Y107775D01*
X211000D01*
X214175Y104600D01*
X227894D01*
G01X209900Y120900D02*
X208950Y119950D01*
X204950D01*
X196350Y128550D01*
X190232D01*
X180250Y138532D01*
Y148161D01*
X177936Y150475D01*
X176464D01*
X167809Y141820D01*
X140569D01*
X137490Y144899D01*
X132067D01*
X129974Y142806D01*
Y135326D01*
X130300Y135000D01*
G01X133786Y134700D02*
X160700D01*
X175500Y119900D01*
X177100D01*
X192084Y104916D01*
X197411D01*
X199278Y103049D01*
X215568D01*
X217417Y101200D01*
X227800D01*
G01X130563Y125200D02*
X134300D01*
X134975Y124525D01*
X139243D01*
X143500Y128782D01*
X156404D01*
X179300Y105886D01*
Y98511D01*
X179775Y98036D01*
Y96840D01*
X180890Y95725D01*
X182574D01*
X184489Y97640D01*
Y98641D01*
X187064Y101216D01*
X195877D01*
X198318Y98775D01*
X207225D01*
X209825Y96175D01*
X224775D01*
X226500Y94450D01*
G01X167581Y164084D02*
X170000Y161665D01*
Y159400D01*
X164575Y153975D01*
X162164D01*
X161189Y153000D01*
X155853D01*
X152480Y149627D01*
X147100D01*
X146227Y150500D01*
X142300D01*
X140000Y148200D01*
X133317D01*
X128524Y143407D01*
Y134265D01*
X129939Y132850D01*
X160250D01*
X186600Y106500D01*
X187500D01*
G01X131500Y149000D02*
X126674Y144174D01*
Y133498D01*
X129172Y131000D01*
X157497D01*
X181150Y107347D01*
Y99278D01*
X181625Y98803D01*
Y97607D01*
X181732Y97500D01*
G01X136156Y138025D02*
X138501Y140370D01*
X173830D01*
X201225Y112975D01*
X202386D01*
X206136Y109225D01*
X217336D01*
X218061Y108500D01*
X227804D01*
X228000Y108304D01*
G01X201650Y111200D02*
X199400D01*
X172005Y138595D01*
X146400D01*
G01X146980Y200580D02*
X151809D01*
X153264Y199125D01*
X198119D01*
X198519Y198725D01*
X204540D01*
X222200Y181065D01*
Y179689D01*
X224068Y177821D01*
X225429D01*
X231105Y172145D01*
Y172141D01*
X233966Y169280D01*
X241400D01*
X263455Y147225D01*
X272136D01*
X274075Y149164D01*
Y156023D01*
X273900Y156198D01*
G01X146396Y207675D02*
Y209113D01*
X150908Y213625D01*
X155109D01*
X157109Y211625D01*
X161000D01*
X162500Y213125D01*
X188503D01*
X188553Y213075D01*
X214646D01*
X229821Y197900D01*
X235800D01*
X236700Y198800D01*
X240700D01*
X243064Y196436D01*
Y195184D01*
X245398Y192850D01*
X256750D01*
X261300Y188300D01*
G01X142997Y207891D02*
Y208331D01*
X150641Y215975D01*
X188270D01*
X189320Y214925D01*
X215413D01*
X230588Y199750D01*
X235033D01*
X235933Y200650D01*
X241467D01*
X244914Y197203D01*
Y195951D01*
X246165Y194700D01*
X259500D01*
X262700Y191500D01*
G01X150000Y210100D02*
X151675Y211775D01*
X154342D01*
X156342Y209775D01*
X162275D01*
X163775Y211275D01*
X187736D01*
X187786Y211225D01*
X213879D01*
X229054Y196050D01*
X235764D01*
X238214Y193600D01*
X241400D01*
X244000Y191000D01*
X252134D01*
X253300Y189834D01*
G01X153500Y210000D02*
X155725Y207775D01*
X167925D01*
X170136Y205564D01*
X187835D01*
X190971Y208700D01*
X213787D01*
X231487Y191000D01*
X240100D01*
G01X206605Y121741D02*
X206234D01*
X181700Y146275D01*
Y148762D01*
X178537Y151925D01*
X175863D01*
X170638Y146700D01*
X159825D01*
X157500Y149025D01*
G01X241200Y94900D02*
X236750Y99350D01*
X216137D01*
X214288Y101199D01*
X198511D01*
X196644Y103066D01*
X186297D01*
X182639Y99408D01*
Y98407D01*
X181732Y97500D01*
G01X230875Y106300D02*
Y107940D01*
X228736Y110079D01*
X218675D01*
X217979Y110775D01*
X209225D01*
X207464Y112536D01*
Y113615D01*
X206425Y114654D01*
X201935D01*
X178700Y137889D01*
Y147200D01*
X177200Y148700D01*
G01X297000Y160200D02*
X293300D01*
X285702Y167798D01*
X276897D01*
X274345Y170350D01*
X263267D01*
X244467Y189150D01*
X226233D01*
X217758Y197625D01*
X214364D01*
X207264Y204725D01*
X200864D01*
X199215Y206374D01*
X198198D01*
G01X278000Y141900D02*
Y142000D01*
X274625Y145375D01*
X255886D01*
X235531Y165730D01*
X232185D01*
X231146Y166769D01*
Y169483D01*
X229255Y171374D01*
Y171378D01*
X224662Y175971D01*
X223101D01*
X210532Y188540D01*
X207861D01*
G01X241200Y94900D02*
X241600Y94500D01*
X249500D01*
X253675Y90325D01*
X266349D01*
X269499Y93475D01*
X276113D01*
X281005Y98367D01*
Y99105D01*
G01X744100Y221900D02*
X744996D01*
X761912Y238816D01*
Y271132D01*
X751068Y281976D01*
X358976D01*
X338100Y261100D01*
X302900D01*
X301500Y262500D01*
Y263700D01*
X298175Y267025D01*
X292165D01*
X288165Y271025D01*
X278025D01*
X263600Y256600D01*
Y252700D01*
G01X265500Y249300D02*
Y254136D01*
X270764Y259400D01*
X338451D01*
X359577Y280526D01*
X750467D01*
X760087Y270906D01*
Y240536D01*
X742100Y222549D01*
Y220951D01*
X745600Y217451D01*
Y213300D01*
X743300Y211000D01*
X743000D01*
G01X267275Y253400D02*
X271675Y257800D01*
X338902D01*
X360178Y279076D01*
X749557D01*
X750900Y277733D01*
Y258600D01*
X757872Y251628D01*
Y240372D01*
X740600Y223100D01*
Y220400D01*
X743800Y217200D01*
Y215900D01*
G01X269800Y250700D02*
Y251111D01*
X274836Y256147D01*
X339442D01*
X360370Y277075D01*
X746486D01*
X749750Y273811D01*
Y257557D01*
X754500Y252807D01*
Y240000D01*
X739050Y224550D01*
Y219750D01*
X741775Y217025D01*
Y214475D01*
X740100Y212800D01*
X739900D01*
G01X331200Y88600D02*
X356472D01*
X393983Y51089D01*
X422411D01*
X431775Y41725D01*
Y29133D01*
X430000Y27358D01*
G01Y30758D02*
X428000Y32758D01*
Y43307D01*
X421768Y49539D01*
X392829D01*
X354993Y87375D01*
X335971D01*
X335771Y87175D01*
X329425D01*
X329300Y87300D01*
G01X466500Y272800D02*
X499300D01*
X502165Y275665D01*
X746835D01*
X749000Y273500D01*
Y256114D01*
X752900Y252214D01*
Y241400D01*
X737500Y226000D01*
Y218600D01*
X739800Y216300D01*
G54D15*
G01X46800Y274500D02*
Y235800D01*
X56000Y226600D01*
X57600D01*
G01X66500Y128000D02*
X66000Y127500D01*
X55943D01*
X52643Y130800D01*
G01X57600Y136900D02*
X78558D01*
X92908Y122550D01*
X119723D01*
X120273Y123100D01*
X130870D01*
X131320Y122650D01*
X142443D01*
X146700Y126907D01*
X155627D01*
X175900Y106634D01*
Y94730D01*
X178674Y91956D01*
X184214D01*
X186364Y94106D01*
Y97463D01*
X188236Y99335D01*
X195106D01*
X200741Y93700D01*
X217419D01*
X218769Y92350D01*
X235034D01*
X235084Y92400D01*
X239600D01*
X240000Y92000D01*
X248900D01*
X252750Y88150D01*
X267250D01*
X269400Y90300D01*
X278900D01*
X280100Y89100D01*
G01X57800Y253900D02*
X59700D01*
X61425Y252175D01*
Y223739D01*
X57492Y219806D01*
X57287D01*
G01X74000Y271400D02*
X77500D01*
X83150Y277050D01*
X172574D01*
X182124Y267500D01*
X233100D01*
X236900Y271300D01*
X267000D01*
G01X111900Y209000D02*
Y207923D01*
X118623Y201200D01*
X130100D01*
X134450Y205550D01*
X163743D01*
X163793Y205600D01*
X166900D01*
X169111Y203389D01*
X199124D01*
X200063Y202450D01*
X206463D01*
X213464Y195449D01*
X213851D01*
X215100Y194200D01*
G01X202200Y89500D02*
X199900Y87200D01*
X193700D01*
X189700Y83200D01*
X179700D01*
X178600Y84300D01*
X164200D01*
X159750Y88750D01*
X139652D01*
X138500Y89902D01*
X136469D01*
G01X133558Y91779D02*
X133600Y91737D01*
Y89670D01*
X136720Y86550D01*
X158838D01*
X163288Y82100D01*
X177600D01*
X178700Y81000D01*
X189500D01*
X192300Y78200D01*
X198800D01*
X210400Y89800D01*
X215200D01*
X216604Y88396D01*
X236596D01*
X236700Y88500D01*
G01X130315Y90533D02*
Y86985D01*
X135300Y82000D01*
X160276D01*
X162376Y79900D01*
X176300D01*
X180200Y76000D01*
X199712D01*
X211312Y87600D01*
X213400D01*
X214804Y86196D01*
X238796D01*
X240700Y88100D01*
X247284D01*
X251134Y84250D01*
X298100D01*
X299800Y85950D01*
G01X244800Y100700D02*
Y105593D01*
X233889Y116504D01*
X223036D01*
X207390Y132150D01*
Y135160D01*
X202550Y140000D01*
X190875D01*
X183575Y147300D01*
Y149539D01*
X179314Y153800D01*
X175086D01*
X170486Y149200D01*
X160780D01*
X158855Y151125D01*
X156630D01*
X153257Y147752D01*
X150352D01*
X147808Y145208D01*
G01X216000Y219500D02*
X217451D01*
X232560Y204391D01*
Y204250D01*
G01X449734Y18681D02*
X448352Y20063D01*
Y27852D01*
X423240Y52964D01*
X394760D01*
X358024Y89700D01*
X333000D01*
X332350Y90350D01*
X327550D01*
X326888Y89688D01*
X323643D01*
X322831Y90500D01*
X320200D01*
X318906Y89206D01*
X311994D01*
X308300Y92900D01*
X302000D01*
X301600Y93300D01*
G54D25*
G01X37600Y198800D02*
Y200150D01*
X38050Y200600D01*
X60000D01*
X61325Y199275D01*
X76686D01*
X82261Y193700D01*
X98300D01*
X105000Y187000D01*
X131439D01*
X135939Y191500D01*
X138600D01*
X140775Y189325D01*
X188836D01*
X195411Y182750D01*
X198002D01*
X203815Y176936D01*
Y176937D01*
X209306Y171446D01*
X213504D01*
X261368Y123582D01*
X303500D01*
G01X37600Y203700D02*
Y202350D01*
X38050Y201900D01*
X60539D01*
X61864Y200575D01*
X64085D01*
X64925Y201415D01*
X66275D01*
X67115Y200575D01*
X68465D01*
X69305Y201415D01*
X70655D01*
X71495Y200575D01*
X77225D01*
X82800Y195000D01*
X85950D01*
X86790Y195840D01*
X88140D01*
X88980Y195000D01*
X90330D01*
X91170Y195840D01*
X92520D01*
X93360Y195000D01*
X98839D01*
X105539Y188300D01*
X130900D01*
X135400Y192800D01*
X139139D01*
X141314Y190625D01*
X189375D01*
X195950Y184050D01*
X198541D01*
X199496Y183095D01*
X200684D01*
X201638Y182141D01*
Y180953D01*
X202593Y179998D01*
X203781D01*
X204735Y179044D01*
Y177856D01*
X205690Y176901D01*
X206878D01*
X207832Y175947D01*
Y174759D01*
X209845Y172746D01*
X214043D01*
X261907Y124882D01*
X303500D01*
G01X303000Y130000D02*
X294961D01*
X292611Y132350D01*
X291261D01*
X290421Y131510D01*
X289071D01*
X288231Y132350D01*
X286881D01*
X286041Y131510D01*
X284691D01*
X283851Y132350D01*
X272176D01*
X271336Y131510D01*
X269986D01*
X269146Y132350D01*
X267796D01*
X266956Y131510D01*
X265606D01*
X264766Y132350D01*
X259036D01*
X215187Y176199D01*
X212857D01*
X204700Y184356D01*
Y192200D01*
X203675Y193225D01*
X197757D01*
X196357Y194625D01*
X145400D01*
X142170Y197855D01*
X135794D01*
X132330Y194391D01*
X105534D01*
X93500Y206425D01*
X48775D01*
X45600Y209600D01*
X41300D01*
X40400Y208700D01*
Y207800D01*
G01X303000Y131300D02*
X295500D01*
X293150Y133650D01*
X259575D01*
X215726Y177499D01*
X213396D01*
X206000Y184895D01*
Y192739D01*
X204214Y194525D01*
X198296D01*
X196896Y195925D01*
X145939D01*
X142709Y199155D01*
X135255D01*
X131791Y195691D01*
X106073D01*
X94039Y207725D01*
X49314D01*
X46139Y210900D01*
X40900D01*
X40400Y211400D01*
Y212700D01*
G01X330100Y98000D02*
X329500Y98600D01*
X327961D01*
X326625Y99936D01*
Y101174D01*
X325474Y102325D01*
X296625D01*
X293850Y105100D01*
X279039D01*
X273564Y99625D01*
X266232D01*
X259093Y106764D01*
X250836D01*
X236600Y121000D01*
X222394D01*
X212500Y130894D01*
Y140000D01*
X209600Y142900D01*
X192216D01*
X187641Y147475D01*
Y150000D01*
X168400Y169241D01*
Y172580D01*
X167140Y173840D01*
G01X330100Y100200D02*
X329800Y99900D01*
X328500D01*
X327925Y100475D01*
Y101713D01*
X326013Y103625D01*
X297164D01*
X294389Y106400D01*
X278500D01*
X273025Y100925D01*
X266771D01*
X259632Y108064D01*
X251375D01*
X237139Y122300D01*
X222933D01*
X213800Y131433D01*
Y140539D01*
X210139Y144200D01*
X192755D01*
X188941Y148014D01*
Y150539D01*
X169700Y169780D01*
Y172630D01*
X170910Y173840D01*
G01X177159Y172900D02*
X178496Y171563D01*
Y170000D01*
X177500Y169004D01*
Y165446D01*
X186846Y156100D01*
X207008D01*
X220000Y143108D01*
Y134500D01*
X226000Y128500D01*
X239850D01*
X253900Y114450D01*
X274312D01*
X276160Y112600D01*
X297401D01*
X301976Y108025D01*
X325680D01*
X328300Y110645D01*
Y112400D01*
G01X180931Y172985D02*
X179796Y171850D01*
Y169461D01*
X178800Y168465D01*
Y165985D01*
X187385Y157400D01*
X207547D01*
X221300Y143647D01*
Y135039D01*
X226539Y129800D01*
X229740D01*
X230580Y130640D01*
X231930D01*
X232770Y129800D01*
X234120D01*
X234960Y130640D01*
X236310D01*
X237150Y129800D01*
X240389D01*
X254439Y115750D01*
X274851D01*
X276699Y113900D01*
X297940D01*
X302515Y109325D01*
X316381D01*
X317221Y110165D01*
X318571D01*
X319411Y109325D01*
X320761D01*
X321601Y110165D01*
X322951D01*
X323791Y109325D01*
X325141D01*
X327000Y111184D01*
Y112400D01*
G01X201899Y134200D02*
X202900Y133199D01*
Y130800D01*
X221221Y112479D01*
X232221D01*
X237825Y106875D01*
Y101836D01*
X242661Y97000D01*
X250395D01*
X254670Y92725D01*
X265354D01*
X268504Y95875D01*
X275118D01*
X280593Y101350D01*
X291436D01*
X292661Y100125D01*
X307136D01*
X312036Y95225D01*
X325036D01*
X325961Y94300D01*
X329713D01*
X330288Y94875D01*
X330913D01*
X333200Y97162D01*
Y97811D01*
X333889Y98500D01*
X339211D01*
X342211Y95500D01*
X351113D01*
X356937Y101324D01*
X365442D01*
X375596Y111478D01*
Y128096D01*
X378850Y131350D01*
X379600D01*
G01X197140Y152010D02*
Y150660D01*
X199850Y147950D01*
X211693D01*
X217550Y142093D01*
Y132987D01*
X224487Y126050D01*
X238789D01*
X253025Y111814D01*
X261186D01*
X268325Y104675D01*
X271471D01*
X276946Y110150D01*
X296089D01*
X299739Y106500D01*
X327091D01*
X332265Y111674D01*
X334567D01*
X335155Y111086D01*
X345966D01*
X348480Y113600D01*
Y116119D01*
X350636Y118275D01*
X364836D01*
X367599Y121038D01*
X371325D01*
X372700Y119663D01*
G01X194623Y149723D02*
X196238D01*
X199311Y146650D01*
X211154D01*
X216250Y141554D01*
Y132448D01*
X223948Y124750D01*
X238250D01*
X252486Y110514D01*
X260647D01*
X267786Y103375D01*
X272010D01*
X277485Y108850D01*
X295550D01*
X299200Y105200D01*
X327630D01*
X328585Y106155D01*
X329773D01*
X330727Y107109D01*
Y108297D01*
X332804Y110374D01*
X334028D01*
X334616Y109786D01*
X335966D01*
X336806Y108946D01*
X338156D01*
X338996Y109786D01*
X340346D01*
X341186Y108946D01*
X342536D01*
X343376Y109786D01*
X346505D01*
X349780Y113061D01*
Y115580D01*
X351175Y116975D01*
X352525D01*
X353365Y116135D01*
X354715D01*
X355555Y116975D01*
X365375D01*
X368138Y119738D01*
X369925D01*
X370100Y119563D01*
G01X205380Y134200D02*
X204200Y133020D01*
Y131339D01*
X221760Y113779D01*
X232760D01*
X239125Y107414D01*
Y102375D01*
X243200Y98300D01*
X250934D01*
X255209Y94025D01*
X264815D01*
X267965Y97175D01*
X274579D01*
X280054Y102650D01*
X291975D01*
X293200Y101425D01*
X307675D01*
X312575Y96525D01*
X325575D01*
X326500Y95600D01*
X329174D01*
X329749Y96175D01*
X330374D01*
X331900Y97701D01*
Y98350D01*
X333350Y99800D01*
X339750D01*
X342750Y96800D01*
X350574D01*
X356398Y102624D01*
X364903D01*
X374296Y112017D01*
Y128635D01*
X378311Y132650D01*
X379600D01*
G01X301721Y114193D02*
X299239Y116675D01*
X284886D01*
X283261Y118300D01*
X259400D01*
X244294Y133406D01*
X243106D01*
X242152Y134360D01*
Y135548D01*
X241197Y136503D01*
X240009D01*
X239055Y137457D01*
Y138645D01*
X237100Y140600D01*
X236185D01*
X234875Y139290D01*
G01X302641Y115113D02*
X302640D01*
X299778Y117975D01*
X285425D01*
X283800Y119600D01*
X259939D01*
X237639Y141900D01*
X236035D01*
X234875Y143060D01*
G54D16*
G01X361600Y159250D02*
X359850Y157500D01*
X357658D01*
X357129Y158030D01*
G54D17*
G01X17500Y190200D02*
Y192300D01*
X19200Y194000D01*
X31400D01*
X33500Y196100D01*
G01X118077Y171180D02*
X111000Y164103D01*
Y157127D01*
X124399Y143728D01*
Y132555D01*
X127100Y129854D01*
Y129580D01*
X127500Y129180D01*
G01X245450Y202050D02*
X243585D01*
X242710Y202925D01*
X240860D01*
X240858Y202927D01*
X238974D01*
X238973Y202926D01*
X234490D01*
X233589Y202025D01*
X231673D01*
X216498Y217200D01*
X215046D01*
X215045Y217201D01*
X213079D01*
X213078Y217200D01*
X190263D01*
X189213Y218250D01*
X138250D01*
X128000Y208000D01*
Y203300D01*
G01X261000Y247500D02*
Y257000D01*
X277000Y273000D01*
X288984D01*
X292984Y269000D01*
X299200D01*
X304300Y263900D01*
Y262900D01*
G01X357129Y158030D02*
X354776D01*
X354246Y157500D01*
X348836D01*
X347711Y158625D01*
X340625D01*
X338450Y156450D01*
X329600D01*
X326178Y159872D01*
X323928D01*
X322650Y161150D01*
G01X393000Y275000D02*
X388000Y270000D01*
Y253200D01*
X379400Y244600D01*
X375300D01*
X373000Y242300D01*
G54D18*
G01X296811Y263386D02*
X288406D01*
X286393Y265399D01*
X278824D01*
X276811Y263386D01*
G01X477913Y45276D02*
X457913D01*
G54D19*
G01X82000Y177500D02*
Y176900D01*
X109150Y149750D01*
Y142082D01*
X112682Y138550D01*
X114597D01*
X117750Y135397D01*
Y134419D01*
X118500Y133669D01*
Y125500D01*
M02*
